FILE_TYPE = MACRO_DRAWING;
SET COLOR_WIRE YELLOW;
SET COLOR_PROP MONO;
SET COLOR_DOT WHITE;
SET COLOR_ARC YELLOW;
SET COLOR_BODY GREEN;
SET COLOR_NOTE MONO;
SET PROP_DISPLAY VALUE;
SET PAGE_NUMBER P144;
FORCEADD OFFPAGE..5
(-7350 -1900);
FORCEPROP 2 LAST $XR0 159 
J 0
(-7635 -1900);
DISPLAY 0.638298 (-7635 -1900);
PAINT MONO (-7635 -1900);
FORCEPROP 2 LAST PATH I100
J 0
(-7625 -1850);
DISPLAY 1.021277 (-7625 -1850);
PAINT ORANGE (-7625 -1850);
DISPLAY INVISIBLE (-7625 -1850);
FORCEPROP 2 LAST CDS_LIB mstr_standard
J 0
(-7350 -1900);
PAINT MONO (-7350 -1900);
DISPLAY INVISIBLE (-7350 -1900);
FORCEPROP 1 LAST OFFPAGE TRUE
J 0
(-7025 -2025);
DISPLAY 0.872340 (-7025 -2025);
PAINT GREEN (-7025 -2025);
DISPLAY INVISIBLE (-7025 -2025);
FORCEPROP 1 LAST COMMENT_BODY TRUE
J 0
(-7250 -1975);
DISPLAY 0.872340 (-7250 -1975);
PAINT GREEN (-7250 -1975);
DISPLAY INVISIBLE (-7250 -1975);
FORCEADD OFFPAGE..5
(-7350 -2950);
FORCEPROP 2 LAST $XR0 160 
J 0
(-7635 -2950);
DISPLAY 0.638298 (-7635 -2950);
PAINT MONO (-7635 -2950);
FORCEPROP 2 LAST PATH I101
J 0
(-7625 -2900);
DISPLAY 1.021277 (-7625 -2900);
PAINT ORANGE (-7625 -2900);
DISPLAY INVISIBLE (-7625 -2900);
FORCEPROP 2 LAST CDS_LIB mstr_standard
J 0
(-7350 -2950);
PAINT MONO (-7350 -2950);
DISPLAY INVISIBLE (-7350 -2950);
FORCEPROP 1 LAST OFFPAGE TRUE
J 0
(-7025 -3075);
DISPLAY 0.872340 (-7025 -3075);
PAINT GREEN (-7025 -3075);
DISPLAY INVISIBLE (-7025 -3075);
FORCEPROP 1 LAST COMMENT_BODY TRUE
J 0
(-7250 -3025);
DISPLAY 0.872340 (-7250 -3025);
PAINT GREEN (-7250 -3025);
DISPLAY INVISIBLE (-7250 -3025);
FORCEADD OFFPAGE..3
R 2
(-7350 -2900);
FORCEPROP 2 LAST $XR0 160 
J 0
(-7630 -2900);
DISPLAY 0.638298 (-7630 -2900);
PAINT MONO (-7630 -2900);
FORCEPROP 2 LAST PATH I102
J 0
(-7650 -2850);
DISPLAY 1.021277 (-7650 -2850);
PAINT ORANGE (-7650 -2850);
DISPLAY INVISIBLE (-7650 -2850);
FORCEPROP 2 LAST CDS_LIB mstr_standard
J 0
(-7350 -2900);
PAINT MONO (-7350 -2900);
DISPLAY INVISIBLE (-7350 -2900);
FORCEPROP 2 LAST ROOM BMC
J 2
(-7825 -2850);
PAINT MONO (-7825 -2850);
DISPLAY INVISIBLE (-7825 -2850);
FORCEPROP 2 LAST BOM_COST SM_CONTROLLER
J 2
(-7825 -2850);
PAINT MONO (-7825 -2850);
DISPLAY INVISIBLE (-7825 -2850);
FORCEPROP 1 LAST OFFPAGE TRUE
J 2
(-7675 -3025);
PAINT GREEN (-7675 -3025);
DISPLAY INVISIBLE (-7675 -3025);
FORCEPROP 1 LAST COMMENT_BODY TRUE
J 2
(-7300 -3000);
DISPLAY 1.170213 (-7300 -3000);
PAINT GREEN (-7300 -3000);
DISPLAY INVISIBLE (-7300 -3000);
FORCEADD OFFPAGE..3
R 2
(-7350 -1850);
FORCEPROP 2 LAST $XR0 159 
J 0
(-7630 -1850);
DISPLAY 0.638298 (-7630 -1850);
PAINT MONO (-7630 -1850);
FORCEPROP 1 LAST COMMENT_BODY TRUE
J 2
(-7300 -1950);
DISPLAY 1.170213 (-7300 -1950);
PAINT GREEN (-7300 -1950);
DISPLAY INVISIBLE (-7300 -1950);
FORCEPROP 1 LAST OFFPAGE TRUE
J 2
(-7675 -1975);
PAINT GREEN (-7675 -1975);
DISPLAY INVISIBLE (-7675 -1975);
FORCEPROP 2 LAST ROOM BMC
J 2
(-7825 -1800);
PAINT MONO (-7825 -1800);
DISPLAY INVISIBLE (-7825 -1800);
FORCEPROP 2 LAST BOM_COST SM_CONTROLLER
J 2
(-7825 -1800);
PAINT MONO (-7825 -1800);
DISPLAY INVISIBLE (-7825 -1800);
FORCEPROP 2 LAST CDS_LIB mstr_standard
J 0
(-7350 -1850);
PAINT MONO (-7350 -1850);
DISPLAY INVISIBLE (-7350 -1850);
FORCEPROP 2 LAST PATH I103
J 0
(-7650 -1800);
DISPLAY 1.021277 (-7650 -1800);
PAINT ORANGE (-7650 -1800);
DISPLAY INVISIBLE (-7650 -1800);
FORCEADD OFFPAGE..5
(-7350 -2200);
FORCEPROP 2 LAST $XR0 167 
J 0
(-7635 -2200);
DISPLAY 0.638298 (-7635 -2200);
PAINT MONO (-7635 -2200);
FORCEPROP 2 LAST PATH I104
J 0
(-7625 -2150);
DISPLAY 1.021277 (-7625 -2150);
PAINT ORANGE (-7625 -2150);
DISPLAY INVISIBLE (-7625 -2150);
FORCEPROP 2 LAST CDS_LIB mstr_standard
J 0
(-7350 -2200);
PAINT MONO (-7350 -2200);
DISPLAY INVISIBLE (-7350 -2200);
FORCEPROP 1 LAST OFFPAGE TRUE
J 0
(-7025 -2325);
DISPLAY 0.872340 (-7025 -2325);
PAINT GREEN (-7025 -2325);
DISPLAY INVISIBLE (-7025 -2325);
FORCEPROP 1 LAST COMMENT_BODY TRUE
J 0
(-7250 -2275);
DISPLAY 0.872340 (-7250 -2275);
PAINT GREEN (-7250 -2275);
DISPLAY INVISIBLE (-7250 -2275);
FORCEADD OFFPAGE..3
R 2
(-7350 -2150);
FORCEPROP 2 LAST $XR0 167 
J 0
(-7630 -2150);
DISPLAY 0.638298 (-7630 -2150);
PAINT MONO (-7630 -2150);
FORCEPROP 1 LAST COMMENT_BODY TRUE
J 2
(-7300 -2250);
DISPLAY 1.170213 (-7300 -2250);
PAINT GREEN (-7300 -2250);
DISPLAY INVISIBLE (-7300 -2250);
FORCEPROP 1 LAST OFFPAGE TRUE
J 2
(-7675 -2275);
PAINT GREEN (-7675 -2275);
DISPLAY INVISIBLE (-7675 -2275);
FORCEPROP 2 LAST ROOM BMC
J 2
(-7825 -2100);
PAINT MONO (-7825 -2100);
DISPLAY INVISIBLE (-7825 -2100);
FORCEPROP 2 LAST BOM_COST SM_CONTROLLER
J 2
(-7825 -2100);
PAINT MONO (-7825 -2100);
DISPLAY INVISIBLE (-7825 -2100);
FORCEPROP 2 LAST CDS_LIB mstr_standard
J 0
(-7350 -2150);
PAINT MONO (-7350 -2150);
DISPLAY INVISIBLE (-7350 -2150);
FORCEPROP 2 LAST PATH I105
J 0
(-7650 -2100);
DISPLAY 1.021277 (-7650 -2100);
PAINT ORANGE (-7650 -2100);
DISPLAY INVISIBLE (-7650 -2100);
FORCEADD OFFPAGE..3
R 2
(-7350 -2450);
FORCEPROP 2 LAST $XR0 159 
J 0
(-7630 -2450);
DISPLAY 0.638298 (-7630 -2450);
PAINT MONO (-7630 -2450);
FORCEPROP 1 LAST COMMENT_BODY TRUE
J 2
(-7300 -2550);
DISPLAY 1.170213 (-7300 -2550);
PAINT GREEN (-7300 -2550);
DISPLAY INVISIBLE (-7300 -2550);
FORCEPROP 1 LAST OFFPAGE TRUE
J 2
(-7675 -2575);
PAINT GREEN (-7675 -2575);
DISPLAY INVISIBLE (-7675 -2575);
FORCEPROP 2 LAST BOM_COST SM_CONTROLLER
J 2
(-7825 -2400);
PAINT MONO (-7825 -2400);
DISPLAY INVISIBLE (-7825 -2400);
FORCEPROP 2 LAST ROOM BMC
J 2
(-7825 -2400);
PAINT MONO (-7825 -2400);
DISPLAY INVISIBLE (-7825 -2400);
FORCEPROP 2 LAST CDS_LIB mstr_standard
J 0
(-7350 -2450);
PAINT MONO (-7350 -2450);
DISPLAY INVISIBLE (-7350 -2450);
FORCEPROP 2 LAST PATH I106
J 0
(-7650 -2400);
DISPLAY 1.021277 (-7650 -2400);
PAINT ORANGE (-7650 -2400);
DISPLAY INVISIBLE (-7650 -2400);
FORCEADD OFFPAGE..5
(-7350 -2500);
FORCEPROP 2 LAST $XR0 159 
J 0
(-7635 -2500);
DISPLAY 0.638298 (-7635 -2500);
PAINT MONO (-7635 -2500);
FORCEPROP 2 LAST PATH I107
J 0
(-7625 -2450);
DISPLAY 1.021277 (-7625 -2450);
PAINT ORANGE (-7625 -2450);
DISPLAY INVISIBLE (-7625 -2450);
FORCEPROP 2 LAST CDS_LIB mstr_standard
J 0
(-7350 -2500);
PAINT MONO (-7350 -2500);
DISPLAY INVISIBLE (-7350 -2500);
FORCEPROP 1 LAST OFFPAGE TRUE
J 0
(-7025 -2625);
DISPLAY 0.872340 (-7025 -2625);
PAINT GREEN (-7025 -2625);
DISPLAY INVISIBLE (-7025 -2625);
FORCEPROP 1 LAST COMMENT_BODY TRUE
J 0
(-7250 -2575);
DISPLAY 0.872340 (-7250 -2575);
PAINT GREEN (-7250 -2575);
DISPLAY INVISIBLE (-7250 -2575);
FORCEADD OFFPAGE..5
(-7350 -2350);
FORCEPROP 2 LAST $XR0 159 
J 0
(-7635 -2350);
DISPLAY 0.638298 (-7635 -2350);
PAINT MONO (-7635 -2350);
FORCEPROP 2 LAST CDS_LIB mstr_standard
J 0
(-7350 -2350);
PAINT MONO (-7350 -2350);
DISPLAY INVISIBLE (-7350 -2350);
FORCEPROP 1 LAST OFFPAGE TRUE
J 0
(-7025 -2475);
DISPLAY 0.872340 (-7025 -2475);
PAINT GREEN (-7025 -2475);
DISPLAY INVISIBLE (-7025 -2475);
FORCEPROP 1 LAST COMMENT_BODY TRUE
J 0
(-7250 -2425);
DISPLAY 0.872340 (-7250 -2425);
PAINT GREEN (-7250 -2425);
DISPLAY INVISIBLE (-7250 -2425);
FORCEPROP 2 LAST PATH I108
J 0
(-7625 -2300);
DISPLAY 1.021277 (-7625 -2300);
PAINT ORANGE (-7625 -2300);
DISPLAY INVISIBLE (-7625 -2300);
FORCEADD OFFPAGE..3
R 2
(-7350 -2300);
FORCEPROP 2 LAST $XR0 159 
J 0
(-7630 -2300);
DISPLAY 0.638298 (-7630 -2300);
PAINT MONO (-7630 -2300);
FORCEPROP 2 LAST PATH I109
J 0
(-7650 -2250);
DISPLAY 1.021277 (-7650 -2250);
PAINT ORANGE (-7650 -2250);
DISPLAY INVISIBLE (-7650 -2250);
FORCEPROP 1 LAST COMMENT_BODY TRUE
J 2
(-7300 -2400);
DISPLAY 1.170213 (-7300 -2400);
PAINT GREEN (-7300 -2400);
DISPLAY INVISIBLE (-7300 -2400);
FORCEPROP 1 LAST OFFPAGE TRUE
J 2
(-7675 -2425);
PAINT GREEN (-7675 -2425);
DISPLAY INVISIBLE (-7675 -2425);
FORCEPROP 2 LAST BOM_COST SM_CONTROLLER
J 2
(-7825 -2250);
PAINT MONO (-7825 -2250);
DISPLAY INVISIBLE (-7825 -2250);
FORCEPROP 2 LAST ROOM BMC
J 2
(-7825 -2250);
PAINT MONO (-7825 -2250);
DISPLAY INVISIBLE (-7825 -2250);
FORCEPROP 2 LAST CDS_LIB mstr_standard
J 0
(-7350 -2300);
PAINT MONO (-7350 -2300);
DISPLAY INVISIBLE (-7350 -2300);
FORCEADD OFFPAGE..3
R 2
(-7350 -2750);
FORCEPROP 2 LAST $XR0 159 
J 0
(-7630 -2750);
DISPLAY 0.638298 (-7630 -2750);
PAINT MONO (-7630 -2750);
FORCEPROP 1 LAST COMMENT_BODY TRUE
J 2
(-7300 -2850);
DISPLAY 1.170213 (-7300 -2850);
PAINT GREEN (-7300 -2850);
DISPLAY INVISIBLE (-7300 -2850);
FORCEPROP 1 LAST OFFPAGE TRUE
J 2
(-7675 -2875);
PAINT GREEN (-7675 -2875);
DISPLAY INVISIBLE (-7675 -2875);
FORCEPROP 2 LAST ROOM BMC
J 2
(-7825 -2700);
PAINT MONO (-7825 -2700);
DISPLAY INVISIBLE (-7825 -2700);
FORCEPROP 2 LAST BOM_COST SM_CONTROLLER
J 2
(-7825 -2700);
PAINT MONO (-7825 -2700);
DISPLAY INVISIBLE (-7825 -2700);
FORCEPROP 2 LAST CDS_LIB mstr_standard
J 0
(-7350 -2750);
PAINT MONO (-7350 -2750);
DISPLAY INVISIBLE (-7350 -2750);
FORCEPROP 2 LAST PATH I110
J 0
(-7650 -2700);
DISPLAY 1.021277 (-7650 -2700);
PAINT ORANGE (-7650 -2700);
DISPLAY INVISIBLE (-7650 -2700);
FORCEADD OFFPAGE..5
(-7350 -2800);
FORCEPROP 2 LAST $XR0 159 
J 0
(-7635 -2800);
DISPLAY 0.638298 (-7635 -2800);
PAINT MONO (-7635 -2800);
FORCEPROP 2 LAST PATH I111
J 0
(-7625 -2750);
DISPLAY 1.021277 (-7625 -2750);
PAINT ORANGE (-7625 -2750);
DISPLAY INVISIBLE (-7625 -2750);
FORCEPROP 2 LAST CDS_LIB mstr_standard
J 0
(-7350 -2800);
PAINT MONO (-7350 -2800);
DISPLAY INVISIBLE (-7350 -2800);
FORCEPROP 1 LAST OFFPAGE TRUE
J 0
(-7025 -2925);
DISPLAY 0.872340 (-7025 -2925);
PAINT GREEN (-7025 -2925);
DISPLAY INVISIBLE (-7025 -2925);
FORCEPROP 1 LAST COMMENT_BODY TRUE
J 0
(-7250 -2875);
DISPLAY 0.872340 (-7250 -2875);
PAINT GREEN (-7250 -2875);
DISPLAY INVISIBLE (-7250 -2875);
FORCEADD OFFPAGE..1
R 2
(-2350 -1700);
FORCEPROP 2 LAST $XR2 190 
J 0
(-1954 -1700);
DISPLAY 0.638298 (-1954 -1700);
PAINT MONO (-1954 -1700);
FORCEPROP 2 LAST $XR1 118 
J 0
(-2074 -1700);
DISPLAY 0.638298 (-2074 -1700);
PAINT MONO (-2074 -1700);
FORCEPROP 2 LAST $XR0 21 
J 0
(-2164 -1700);
DISPLAY 0.638298 (-2164 -1700);
PAINT MONO (-2164 -1700);
FORCEPROP 2 LAST CDS_LIB mstr_standard
J 2
(-2350 -1700);
PAINT MONO (-2350 -1700);
DISPLAY INVISIBLE (-2350 -1700);
FORCEPROP 2 LAST ROOM BMC
J 2
(-2100 -1625);
DISPLAY 1.361702 (-2100 -1625);
PAINT ORANGE (-2100 -1625);
DISPLAY INVISIBLE (-2100 -1625);
FORCEPROP 2 LAST BOM_COST SM_CONTROLLER
J 2
(-2800 -1650);
PAINT MONO (-2800 -1650);
DISPLAY INVISIBLE (-2800 -1650);
FORCEPROP 1 LAST OFFPAGE TRUE
J 2
(-2675 -1825);
DISPLAY 0.872340 (-2675 -1825);
PAINT GREEN (-2675 -1825);
DISPLAY INVISIBLE (-2675 -1825);
FORCEPROP 1 LAST COMMENT_BODY TRUE
J 2
(-2475 -1800);
DISPLAY 0.872340 (-2475 -1800);
PAINT GREEN (-2475 -1800);
DISPLAY INVISIBLE (-2475 -1800);
FORCEPROP 2 LAST PATH I112
J 2
(-2150 -1650);
DISPLAY 1.021277 (-2150 -1650);
PAINT ORANGE (-2150 -1650);
DISPLAY INVISIBLE (-2150 -1650);
FORCEADD OFFPAGE..4
(-600 -2800);
FORCEPROP 2 LAST $XR0 190 
J 0
(-414 -2800);
DISPLAY 0.638298 (-414 -2800);
PAINT MONO (-414 -2800);
FORCEPROP 1 LAST COMMENT_BODY TRUE
J 0
(-625 -2900);
DISPLAY 0.872340 (-625 -2900);
PAINT GREEN (-625 -2900);
DISPLAY INVISIBLE (-625 -2900);
FORCEPROP 1 LAST OFFPAGE TRUE
J 0
(-275 -2925);
DISPLAY 0.872340 (-275 -2925);
PAINT GREEN (-275 -2925);
DISPLAY INVISIBLE (-275 -2925);
FORCEPROP 2 LAST CDS_LIB mstr_standard
J 0
(-600 -2800);
PAINT MONO (-600 -2800);
DISPLAY INVISIBLE (-600 -2800);
FORCEPROP 2 LAST PATH I113
J 0
(-400 -2750);
DISPLAY 1.021277 (-400 -2750);
PAINT ORANGE (-400 -2750);
DISPLAY INVISIBLE (-400 -2750);
FORCEADD RES..1
(-1750 -2800);
FORCEPROP 1 LAST MATERIAL CHIP
J 0
(-1800 -2850);
DISPLAY 0.617021 (-1800 -2850);
PAINT SKYBLUE (-1800 -2850);
FORCEPROP 1 LAST PACK_TYPE 0402
J 0
(-1950 -2800);
DISPLAY 0.617021 (-1950 -2800);
PAINT SKYBLUE (-1950 -2800);
FORCEPROP 1 LAST LOCATION R25W70
J 0
(-2500 -2800);
DISPLAY 0.617021 (-2500 -2800);
PAINT AQUA (-2500 -2800);
FORCEPROP 1 LAST VALUE 33.2
J 2
(-2225 -2800);
DISPLAY 0.617021 (-2225 -2800);
PAINT SKYBLUE (-2225 -2800);
FORCEPROP 1 LAST WATTAGE 1/16W
J 2
(-1975 -2800);
DISPLAY 0.617021 (-1975 -2800);
PAINT SKYBLUE (-1975 -2800);
FORCEPROP 1 LAST PART_NUMBER G21796-074
J 0
(-1650 -2800);
DISPLAY 0.617021 (-1650 -2800);
PAINT BLUE (-1650 -2800);
FORCEPROP 1 LAST TOLERANCE 1%
J 0
(-2200 -2800);
DISPLAY 0.617021 (-2200 -2800);
PAINT SKYBLUE (-2200 -2800);
FORCEPROP 1 LASTPIN (-1650 -2800) $PN 2
J 0
(-1688 -2788);
DISPLAY 0.617021 (-1688 -2788);
PAINT ORANGE (-1688 -2788);
FORCEPROP 1 LASTPIN (-1850 -2800) $PN 1
J 0
(-1838 -2788);
DISPLAY 0.617021 (-1838 -2788);
PAINT ORANGE (-1838 -2788);
FORCEPROP 1 LAST PATH I114
J 0
(-1800 -2650);
DISPLAY 0.978723 (-1800 -2650);
PAINT WHITE (-1800 -2650);
DISPLAY INVISIBLE (-1800 -2650);
FORCEPROP 2 LAST CDS_LOCATION R25W70
J 0
(-2300 -2800);
DISPLAY 0.617021 (-2300 -2800);
PAINT AQUA (-2300 -2800);
DISPLAY INVISIBLE (-2300 -2800);
FORCEPROP 2 LAST CDS_LIB mstr_discrete
J 0
(-1750 -2800);
PAINT ORANGE (-1750 -2800);
DISPLAY INVISIBLE (-1750 -2800);
FORCEPROP 0 LAST ROOM BMC
J 0
(-1800 -2650);
DISPLAY 1.021277 (-1800 -2650);
PAINT ORANGE (-1800 -2650);
DISPLAY INVISIBLE (-1800 -2650);
FORCEPROP 0 LAST BOM_COST SM_CONTROLLER
J 0
(-1800 -2600);
DISPLAY 1.021277 (-1800 -2600);
PAINT ORANGE (-1800 -2600);
DISPLAY INVISIBLE (-1800 -2600);
FORCEPROP 2 LAST SEC_TYPE 0402
J 0
(-1800 -2600);
DISPLAY 1.021277 (-1800 -2600);
PAINT ORANGE (-1800 -2600);
DISPLAY INVISIBLE (-1800 -2600);
FORCEPROP 2 LAST SEC 1
J 0
(-1800 -2600);
DISPLAY 0.680851 (-1800 -2600);
PAINT MONO (-1800 -2600);
DISPLAY INVISIBLE (-1800 -2600);
FORCEPROP 0 LAST CDS_SEC 1
J 0
(-1800 -2650);
PAINT MONO (-1800 -2650);
DISPLAY INVISIBLE (-1800 -2650);
FORCEADD OFFPAGE..1
R 2
(-600 -2750);
FORCEPROP 2 LAST $XR0 191 
J 0
(-414 -2750);
DISPLAY 0.638298 (-414 -2750);
PAINT MONO (-414 -2750);
FORCEPROP 2 LAST PATH I116
J 2
(-350 -2700);
DISPLAY 1.021277 (-350 -2700);
PAINT ORANGE (-350 -2700);
DISPLAY INVISIBLE (-350 -2700);
FORCEPROP 2 LAST CDS_LIB mstr_standard
J 2
(-600 -2750);
PAINT MONO (-600 -2750);
DISPLAY INVISIBLE (-600 -2750);
FORCEPROP 1 LAST OFFPAGE TRUE
J 2
(-925 -2875);
DISPLAY 0.872340 (-925 -2875);
PAINT GREEN (-925 -2875);
DISPLAY INVISIBLE (-925 -2875);
FORCEPROP 1 LAST COMMENT_BODY TRUE
J 2
(-725 -2850);
DISPLAY 0.872340 (-725 -2850);
PAINT GREEN (-725 -2850);
DISPLAY INVISIBLE (-725 -2850);
FORCEADD RES..1
(-1750 -2750);
FORCEPROP 1 LAST MATERIAL CHIP
J 0
(-1800 -2700);
DISPLAY 0.617021 (-1800 -2700);
PAINT SKYBLUE (-1800 -2700);
FORCEPROP 1 LAST TOLERANCE 1%
J 0
(-2200 -2750);
DISPLAY 0.617021 (-2200 -2750);
PAINT SKYBLUE (-2200 -2750);
FORCEPROP 1 LAST WATTAGE 1/16W
J 2
(-1975 -2750);
DISPLAY 0.617021 (-1975 -2750);
PAINT SKYBLUE (-1975 -2750);
FORCEPROP 1 LAST PART_NUMBER G21796-074
J 0
(-1650 -2750);
DISPLAY 0.617021 (-1650 -2750);
PAINT BLUE (-1650 -2750);
FORCEPROP 1 LAST LOCATION R25W75
J 0
(-2500 -2750);
DISPLAY 0.617021 (-2500 -2750);
PAINT AQUA (-2500 -2750);
FORCEPROP 1 LAST VALUE 33.2
J 2
(-2225 -2750);
DISPLAY 0.617021 (-2225 -2750);
PAINT SKYBLUE (-2225 -2750);
FORCEPROP 1 LASTPIN (-1850 -2750) $PN 1
J 0
(-1838 -2738);
DISPLAY 0.617021 (-1838 -2738);
PAINT ORANGE (-1838 -2738);
FORCEPROP 1 LASTPIN (-1650 -2750) $PN 2
J 0
(-1688 -2738);
DISPLAY 0.617021 (-1688 -2738);
PAINT ORANGE (-1688 -2738);
FORCEPROP 1 LAST PACK_TYPE 0402
J 0
(-1950 -2750);
DISPLAY 0.617021 (-1950 -2750);
PAINT SKYBLUE (-1950 -2750);
FORCEPROP 1 LAST PATH I118
J 0
(-1800 -2600);
DISPLAY 0.978723 (-1800 -2600);
PAINT WHITE (-1800 -2600);
DISPLAY INVISIBLE (-1800 -2600);
FORCEPROP 0 LAST CDS_SEC 1
J 0
(-1800 -2600);
PAINT MONO (-1800 -2600);
DISPLAY INVISIBLE (-1800 -2600);
FORCEPROP 2 LAST SEC 1
J 0
(-1800 -2550);
DISPLAY 0.680851 (-1800 -2550);
PAINT MONO (-1800 -2550);
DISPLAY INVISIBLE (-1800 -2550);
FORCEPROP 2 LAST SEC_TYPE 0402
J 0
(-1800 -2550);
DISPLAY 1.021277 (-1800 -2550);
PAINT ORANGE (-1800 -2550);
DISPLAY INVISIBLE (-1800 -2550);
FORCEPROP 0 LAST BOM_COST SM_CONTROLLER
J 0
(-1800 -2550);
DISPLAY 1.021277 (-1800 -2550);
PAINT ORANGE (-1800 -2550);
DISPLAY INVISIBLE (-1800 -2550);
FORCEPROP 0 LAST ROOM BMC
J 0
(-1800 -2600);
DISPLAY 1.021277 (-1800 -2600);
PAINT ORANGE (-1800 -2600);
DISPLAY INVISIBLE (-1800 -2600);
FORCEPROP 2 LAST CDS_LIB mstr_discrete
J 0
(-1750 -2750);
PAINT ORANGE (-1750 -2750);
DISPLAY INVISIBLE (-1750 -2750);
FORCEPROP 2 LAST CDS_LOCATION R25W75
J 0
(-2300 -2750);
DISPLAY 0.617021 (-2300 -2750);
PAINT AQUA (-2300 -2750);
DISPLAY INVISIBLE (-2300 -2750);
FORCEADD OFFPAGE..2
(-2350 -2500);
FORCEPROP 2 LAST $XR0 154 
J 0
(-2161 -2500);
DISPLAY 0.638298 (-2161 -2500);
PAINT MONO (-2161 -2500);
FORCEPROP 2 LAST PATH I121
J 0
(-2150 -2450);
DISPLAY 1.021277 (-2150 -2450);
PAINT ORANGE (-2150 -2450);
DISPLAY INVISIBLE (-2150 -2450);
FORCEPROP 1 LAST COMMENT_BODY TRUE
J 0
(-2395 -2595);
DISPLAY 0.872340 (-2395 -2595);
PAINT GREEN (-2395 -2595);
DISPLAY INVISIBLE (-2395 -2595);
FORCEPROP 1 LAST OFFPAGE TRUE
J 0
(-2025 -2625);
DISPLAY 0.872340 (-2025 -2625);
PAINT GREEN (-2025 -2625);
DISPLAY INVISIBLE (-2025 -2625);
FORCEPROP 2 LAST CDS_LIB mstr_standard
J 0
(-2350 -2500);
PAINT MONO (-2350 -2500);
DISPLAY INVISIBLE (-2350 -2500);
FORCEADD OFFPAGE..2
(-2350 -2450);
FORCEPROP 2 LAST $XR0 154 
J 0
(-2161 -2450);
DISPLAY 0.638298 (-2161 -2450);
PAINT MONO (-2161 -2450);
FORCEPROP 2 LAST PATH I125
J 0
(-2150 -2400);
DISPLAY 1.021277 (-2150 -2400);
PAINT ORANGE (-2150 -2400);
DISPLAY INVISIBLE (-2150 -2400);
FORCEPROP 1 LAST COMMENT_BODY TRUE
J 0
(-2395 -2545);
DISPLAY 0.872340 (-2395 -2545);
PAINT GREEN (-2395 -2545);
DISPLAY INVISIBLE (-2395 -2545);
FORCEPROP 1 LAST OFFPAGE TRUE
J 0
(-2025 -2575);
DISPLAY 0.872340 (-2025 -2575);
PAINT GREEN (-2025 -2575);
DISPLAY INVISIBLE (-2025 -2575);
FORCEPROP 2 LAST CDS_LIB mstr_standard
J 0
(-2350 -2450);
PAINT MONO (-2350 -2450);
DISPLAY INVISIBLE (-2350 -2450);
FORCEADD OFFPAGE..2
(-2350 -2350);
FORCEPROP 2 LAST $XR0 154 
J 0
(-2161 -2350);
DISPLAY 0.638298 (-2161 -2350);
PAINT MONO (-2161 -2350);
FORCEPROP 2 LAST PATH I126
J 0
(-2150 -2300);
DISPLAY 1.021277 (-2150 -2300);
PAINT ORANGE (-2150 -2300);
DISPLAY INVISIBLE (-2150 -2300);
FORCEPROP 1 LAST COMMENT_BODY TRUE
J 0
(-2395 -2445);
DISPLAY 0.872340 (-2395 -2445);
PAINT GREEN (-2395 -2445);
DISPLAY INVISIBLE (-2395 -2445);
FORCEPROP 1 LAST OFFPAGE TRUE
J 0
(-2025 -2475);
DISPLAY 0.872340 (-2025 -2475);
PAINT GREEN (-2025 -2475);
DISPLAY INVISIBLE (-2025 -2475);
FORCEPROP 2 LAST CDS_LIB mstr_standard
J 0
(-2350 -2350);
PAINT MONO (-2350 -2350);
DISPLAY INVISIBLE (-2350 -2350);
FORCEADD OFFPAGE..4
(-2350 -2300);
FORCEPROP 2 LAST $XR0 154 
J 0
(-2164 -2300);
DISPLAY 0.638298 (-2164 -2300);
PAINT MONO (-2164 -2300);
FORCEPROP 2 LAST PATH I127
J 0
(-2150 -2250);
DISPLAY 1.021277 (-2150 -2250);
PAINT ORANGE (-2150 -2250);
DISPLAY INVISIBLE (-2150 -2250);
FORCEPROP 1 LAST COMMENT_BODY TRUE
J 0
(-2375 -2400);
DISPLAY 0.872340 (-2375 -2400);
PAINT GREEN (-2375 -2400);
DISPLAY INVISIBLE (-2375 -2400);
FORCEPROP 1 LAST OFFPAGE TRUE
J 0
(-2025 -2425);
DISPLAY 0.872340 (-2025 -2425);
PAINT GREEN (-2025 -2425);
DISPLAY INVISIBLE (-2025 -2425);
FORCEPROP 2 LAST CDS_LIB mstr_standard
J 0
(-2350 -2300);
PAINT MONO (-2350 -2300);
DISPLAY INVISIBLE (-2350 -2300);
FORCEADD OFFPAGE..2
(-2350 -2650);
FORCEPROP 2 LAST $XR1 191 
J 0
(-2041 -2650);
DISPLAY 0.638298 (-2041 -2650);
PAINT MONO (-2041 -2650);
FORCEPROP 2 LAST $XR0 120 
J 0
(-2161 -2650);
DISPLAY 0.638298 (-2161 -2650);
PAINT MONO (-2161 -2650);
FORCEPROP 2 LAST CDS_LIB mstr_standard
J 0
(-2350 -2650);
PAINT MONO (-2350 -2650);
DISPLAY INVISIBLE (-2350 -2650);
FORCEPROP 1 LAST OFFPAGE TRUE
J 0
(-2025 -2775);
DISPLAY 0.872340 (-2025 -2775);
PAINT GREEN (-2025 -2775);
DISPLAY INVISIBLE (-2025 -2775);
FORCEPROP 1 LAST COMMENT_BODY TRUE
J 0
(-2395 -2745);
DISPLAY 0.872340 (-2395 -2745);
PAINT GREEN (-2395 -2745);
DISPLAY INVISIBLE (-2395 -2745);
FORCEPROP 2 LAST PATH I128
J 0
(-1950 -2600);
DISPLAY 1.021277 (-1950 -2600);
PAINT ORANGE (-1950 -2600);
DISPLAY INVISIBLE (-1950 -2600);
FORCEADD OFFPAGE..2
(-2350 -2600);
FORCEPROP 2 LAST $XR2 191 
J 0
(-1921 -2600);
DISPLAY 0.638298 (-1921 -2600);
PAINT MONO (-1921 -2600);
FORCEPROP 2 LAST $XR1 125 
J 0
(-2041 -2600);
DISPLAY 0.638298 (-2041 -2600);
PAINT MONO (-2041 -2600);
FORCEPROP 2 LAST $XR0 119 
J 0
(-2161 -2600);
DISPLAY 0.638298 (-2161 -2600);
PAINT MONO (-2161 -2600);
FORCEPROP 2 LAST PATH I129
J 0
(-1825 -2550);
DISPLAY 1.021277 (-1825 -2550);
PAINT ORANGE (-1825 -2550);
DISPLAY INVISIBLE (-1825 -2550);
FORCEPROP 2 LAST CDS_LIB mstr_standard
J 0
(-2350 -2600);
PAINT MONO (-2350 -2600);
DISPLAY INVISIBLE (-2350 -2600);
FORCEPROP 1 LAST OFFPAGE TRUE
J 0
(-2025 -2725);
DISPLAY 0.872340 (-2025 -2725);
PAINT GREEN (-2025 -2725);
DISPLAY INVISIBLE (-2025 -2725);
FORCEPROP 1 LAST COMMENT_BODY TRUE
J 0
(-2395 -2695);
DISPLAY 0.872340 (-2395 -2695);
PAINT GREEN (-2395 -2695);
DISPLAY INVISIBLE (-2395 -2695);
FORCEADD OFFPAGE..4
R 2
(-7350 -3450);
FORCEPROP 2 LAST $XR1 119 
J 0
(-7752 -3450);
DISPLAY 0.638298 (-7752 -3450);
PAINT MONO (-7752 -3450);
FORCEPROP 2 LAST $XR0 157 
J 0
(-7632 -3450);
DISPLAY 0.638298 (-7632 -3450);
PAINT MONO (-7632 -3450);
FORCEPROP 1 LAST COMMENT_BODY TRUE
J 2
(-7325 -3550);
DISPLAY 0.872340 (-7325 -3550);
PAINT GREEN (-7325 -3550);
DISPLAY INVISIBLE (-7325 -3550);
FORCEPROP 1 LAST OFFPAGE TRUE
J 2
(-7675 -3575);
DISPLAY 0.872340 (-7675 -3575);
PAINT GREEN (-7675 -3575);
DISPLAY INVISIBLE (-7675 -3575);
FORCEPROP 2 LAST CDS_LIB mstr_standard
J 2
(-7350 -3450);
PAINT ORANGE (-7350 -3450);
DISPLAY INVISIBLE (-7350 -3450);
FORCEPROP 2 LAST PATH I130
J 2
(-7675 -3400);
DISPLAY 1.021277 (-7675 -3400);
PAINT ORANGE (-7675 -3400);
DISPLAY INVISIBLE (-7675 -3400);
FORCEADD OFFPAGE..2
(-2350 -3000);
FORCEPROP 2 LAST $XR1 255 
J 0
(-2041 -3000);
DISPLAY 0.638298 (-2041 -3000);
PAINT MONO (-2041 -3000);
FORCEPROP 2 LAST $XR0 189 
J 0
(-2161 -3000);
DISPLAY 0.638298 (-2161 -3000);
PAINT MONO (-2161 -3000);
FORCEPROP 1 LAST OFFPAGE TRUE
J 0
(-2025 -3125);
DISPLAY 0.872340 (-2025 -3125);
PAINT GREEN (-2025 -3125);
DISPLAY INVISIBLE (-2025 -3125);
FORCEPROP 1 LAST COMMENT_BODY TRUE
J 0
(-2395 -3095);
DISPLAY 0.872340 (-2395 -3095);
PAINT GREEN (-2395 -3095);
DISPLAY INVISIBLE (-2395 -3095);
FORCEPROP 2 LAST PATH I133
J 0
(-2175 -2925);
DISPLAY 1.021277 (-2175 -2925);
PAINT ORANGE (-2175 -2925);
DISPLAY INVISIBLE (-2175 -2925);
FORCEPROP 2 LAST CDS_LIB mstr_standard
J 0
(-2350 -3000);
PAINT MONO (-2350 -3000);
DISPLAY INVISIBLE (-2350 -3000);
FORCEADD OFFPAGE..2
(-2350 -2950);
FORCEPROP 2 LAST $XR1 254 
J 0
(-2041 -2950);
DISPLAY 0.638298 (-2041 -2950);
PAINT MONO (-2041 -2950);
FORCEPROP 2 LAST $XR0 189 
J 0
(-2161 -2950);
DISPLAY 0.638298 (-2161 -2950);
PAINT MONO (-2161 -2950);
FORCEPROP 1 LAST OFFPAGE TRUE
J 0
(-2025 -3075);
DISPLAY 0.872340 (-2025 -3075);
PAINT GREEN (-2025 -3075);
DISPLAY INVISIBLE (-2025 -3075);
FORCEPROP 1 LAST COMMENT_BODY TRUE
J 0
(-2395 -3045);
DISPLAY 0.872340 (-2395 -3045);
PAINT GREEN (-2395 -3045);
DISPLAY INVISIBLE (-2395 -3045);
FORCEPROP 2 LAST PATH I134
J 0
(-2175 -2875);
DISPLAY 1.021277 (-2175 -2875);
PAINT ORANGE (-2175 -2875);
DISPLAY INVISIBLE (-2175 -2875);
FORCEPROP 2 LAST CDS_LIB mstr_standard
J 0
(-2350 -2950);
PAINT MONO (-2350 -2950);
DISPLAY INVISIBLE (-2350 -2950);
FORCEADD OFFPAGE..2
(-2350 -2900);
FORCEPROP 2 LAST $XR2 254 
J 0
(-1921 -2900);
DISPLAY 0.638298 (-1921 -2900);
PAINT MONO (-1921 -2900);
FORCEPROP 2 LAST $XR1 245 
J 0
(-2041 -2900);
DISPLAY 0.638298 (-2041 -2900);
PAINT MONO (-2041 -2900);
FORCEPROP 2 LAST $XR0 189 
J 0
(-2161 -2900);
DISPLAY 0.638298 (-2161 -2900);
PAINT MONO (-2161 -2900);
FORCEPROP 2 LAST CDS_LIB mstr_standard
J 0
(-2350 -2900);
PAINT MONO (-2350 -2900);
DISPLAY INVISIBLE (-2350 -2900);
FORCEPROP 2 LAST PATH I135
J 0
(-2175 -2825);
DISPLAY 1.021277 (-2175 -2825);
PAINT ORANGE (-2175 -2825);
DISPLAY INVISIBLE (-2175 -2825);
FORCEPROP 1 LAST COMMENT_BODY TRUE
J 0
(-2395 -2995);
DISPLAY 0.872340 (-2395 -2995);
PAINT GREEN (-2395 -2995);
DISPLAY INVISIBLE (-2395 -2995);
FORCEPROP 1 LAST OFFPAGE TRUE
J 0
(-2025 -3025);
DISPLAY 0.872340 (-2025 -3025);
PAINT GREEN (-2025 -3025);
DISPLAY INVISIBLE (-2025 -3025);
FORCEADD OFFPAGE..2
(-2350 -3200);
FORCEPROP 2 LAST $XR1 252 
J 0
(-2041 -3200);
DISPLAY 0.638298 (-2041 -3200);
PAINT MONO (-2041 -3200);
FORCEPROP 2 LAST $XR0 144 
J 0
(-2161 -3200);
DISPLAY 0.638298 (-2161 -3200);
PAINT MONO (-2161 -3200);
FORCEPROP 1 LAST COMMENT_BODY TRUE
J 0
(-2395 -3295);
DISPLAY 0.872340 (-2395 -3295);
PAINT GREEN (-2395 -3295);
DISPLAY INVISIBLE (-2395 -3295);
FORCEPROP 1 LAST OFFPAGE TRUE
J 0
(-2025 -3325);
DISPLAY 0.872340 (-2025 -3325);
PAINT GREEN (-2025 -3325);
DISPLAY INVISIBLE (-2025 -3325);
FORCEPROP 2 LAST PATH I136
J 0
(-2175 -3125);
DISPLAY 1.021277 (-2175 -3125);
PAINT ORANGE (-2175 -3125);
DISPLAY INVISIBLE (-2175 -3125);
FORCEPROP 2 LAST CDS_LIB mstr_standard
J 0
(-2350 -3200);
PAINT MONO (-2350 -3200);
DISPLAY INVISIBLE (-2350 -3200);
FORCEADD OFFPAGE..2
(-2350 -3250);
FORCEPROP 2 LAST $XR1 252 
J 0
(-2041 -3250);
DISPLAY 0.638298 (-2041 -3250);
PAINT MONO (-2041 -3250);
FORCEPROP 2 LAST $XR0 144 
J 0
(-2161 -3250);
DISPLAY 0.638298 (-2161 -3250);
PAINT MONO (-2161 -3250);
FORCEPROP 1 LAST COMMENT_BODY TRUE
J 0
(-2395 -3345);
DISPLAY 0.872340 (-2395 -3345);
PAINT GREEN (-2395 -3345);
DISPLAY INVISIBLE (-2395 -3345);
FORCEPROP 1 LAST OFFPAGE TRUE
J 0
(-2025 -3375);
DISPLAY 0.872340 (-2025 -3375);
PAINT GREEN (-2025 -3375);
DISPLAY INVISIBLE (-2025 -3375);
FORCEPROP 2 LAST PATH I137
J 0
(-2175 -3175);
DISPLAY 1.021277 (-2175 -3175);
PAINT ORANGE (-2175 -3175);
DISPLAY INVISIBLE (-2175 -3175);
FORCEPROP 2 LAST CDS_LIB mstr_standard
J 0
(-2350 -3250);
PAINT MONO (-2350 -3250);
DISPLAY INVISIBLE (-2350 -3250);
FORCEADD OFFPAGE..2
(-2350 -3300);
FORCEPROP 2 LAST $XR1 252 
J 0
(-2041 -3300);
DISPLAY 0.638298 (-2041 -3300);
PAINT MONO (-2041 -3300);
FORCEPROP 2 LAST $XR0 144 
J 0
(-2161 -3300);
DISPLAY 0.638298 (-2161 -3300);
PAINT MONO (-2161 -3300);
FORCEPROP 1 LAST OFFPAGE TRUE
J 0
(-2025 -3425);
DISPLAY 0.872340 (-2025 -3425);
PAINT GREEN (-2025 -3425);
DISPLAY INVISIBLE (-2025 -3425);
FORCEPROP 1 LAST COMMENT_BODY TRUE
J 0
(-2395 -3395);
DISPLAY 0.872340 (-2395 -3395);
PAINT GREEN (-2395 -3395);
DISPLAY INVISIBLE (-2395 -3395);
FORCEPROP 2 LAST PATH I138
J 0
(-2175 -3225);
DISPLAY 1.021277 (-2175 -3225);
PAINT ORANGE (-2175 -3225);
DISPLAY INVISIBLE (-2175 -3225);
FORCEPROP 2 LAST CDS_LIB mstr_standard
J 0
(-2350 -3300);
PAINT MONO (-2350 -3300);
DISPLAY INVISIBLE (-2350 -3300);
FORCEADD RES..2
R 2
(-2800 -4550);
FORCEPROP 1 LAST PART_NUMBER G21796-009
J 2
(-2840 -4675);
DISPLAY 0.617021 (-2840 -4675);
PAINT BLUE (-2840 -4675);
FORCEPROP 1 LASTPIN (-2800 -4650) $PN 2
J 2
(-2805 -4640);
DISPLAY 0.617021 (-2805 -4640);
PAINT ORANGE (-2805 -4640);
FORCEPROP 1 LAST PACK_TYPE 0402
J 2
(-2840 -4725);
DISPLAY 0.617021 (-2840 -4725);
PAINT SKYBLUE (-2840 -4725);
FORCEPROP 1 LASTPIN (-2800 -4450) $PN 1
J 2
(-2805 -4488);
DISPLAY 0.617021 (-2805 -4488);
PAINT ORANGE (-2805 -4488);
FORCEPROP 1 LAST MATERIAL CHIP
J 2
(-2840 -4625);
DISPLAY 0.617021 (-2840 -4625);
PAINT SKYBLUE (-2840 -4625);
FORCEPROP 1 LAST LOCATION R25W123
J 2
(-2845 -4425);
DISPLAY 0.617021 (-2845 -4425);
PAINT AQUA (-2845 -4425);
FORCEPROP 1 LAST VALUE 150.0
J 2
(-2845 -4475);
DISPLAY 0.617021 (-2845 -4475);
PAINT SKYBLUE (-2845 -4475);
FORCEPROP 1 LAST TOLERANCE 1%
J 2
(-2845 -4525);
DISPLAY 0.617021 (-2845 -4525);
PAINT SKYBLUE (-2845 -4525);
FORCEPROP 1 LAST WATTAGE 1/16W
J 2
(-2840 -4575);
DISPLAY 0.617021 (-2840 -4575);
PAINT SKYBLUE (-2840 -4575);
FORCEPROP 0 LAST GROUP AST2500
J 0
(-3047 -4765);
DISPLAY 0.638298 (-3047 -4765);
PAINT BROWN (-3047 -4765);
DISPLAY BOTH (-3047 -4765);
FORCEPROP 2 LAST CDS_LOCATION R25W123
J 2
(-2845 -4425);
DISPLAY 0.617021 (-2845 -4425);
PAINT AQUA (-2845 -4425);
DISPLAY INVISIBLE (-2845 -4425);
FORCEPROP 2 LAST SEC_TYPE 0402
J 0
(-2850 -4325);
DISPLAY 1.021277 (-2850 -4325);
PAINT ORANGE (-2850 -4325);
DISPLAY INVISIBLE (-2850 -4325);
FORCEPROP 2 LAST BOM_COST PROC_SIDEBAND
J 2
(-2800 -4550);
PAINT MONO (-2800 -4550);
DISPLAY INVISIBLE (-2800 -4550);
FORCEPROP 2 LAST CDS_LIB mstr_discrete
J 0
(-2800 -4550);
PAINT ORANGE (-2800 -4550);
DISPLAY INVISIBLE (-2800 -4550);
FORCEPROP 2 LAST SEC 1
J 0
(-2850 -4325);
DISPLAY 0.680851 (-2850 -4325);
PAINT MONO (-2850 -4325);
DISPLAY INVISIBLE (-2850 -4325);
FORCEPROP 2 LAST ROOM PROC_SIDEBAND
J 2
(-2825 -4775);
PAINT ORANGE (-2825 -4775);
DISPLAY INVISIBLE (-2825 -4775);
FORCEPROP 1 LAST PATH I139
J 2
(-2850 -4375);
DISPLAY 0.978723 (-2850 -4375);
PAINT WHITE (-2850 -4375);
DISPLAY INVISIBLE (-2850 -4375);
FORCEADD RES..2
R 2
(-2450 -4550);
FORCEPROP 1 LAST PART_NUMBER G21796-009
J 2
(-2490 -4675);
DISPLAY 0.617021 (-2490 -4675);
PAINT BLUE (-2490 -4675);
FORCEPROP 1 LAST VALUE 150.0
J 2
(-2495 -4475);
DISPLAY 0.617021 (-2495 -4475);
PAINT SKYBLUE (-2495 -4475);
FORCEPROP 1 LASTPIN (-2450 -4650) $PN 2
J 2
(-2455 -4640);
DISPLAY 0.638298 (-2455 -4640);
PAINT ORANGE (-2455 -4640);
FORCEPROP 1 LASTPIN (-2450 -4450) $PN 1
J 2
(-2455 -4488);
DISPLAY 0.638298 (-2455 -4488);
PAINT ORANGE (-2455 -4488);
FORCEPROP 1 LAST MATERIAL CHIP
J 2
(-2490 -4625);
DISPLAY 0.617021 (-2490 -4625);
PAINT SKYBLUE (-2490 -4625);
FORCEPROP 1 LAST LOCATION R25W124
J 2
(-2495 -4425);
DISPLAY 0.617021 (-2495 -4425);
PAINT AQUA (-2495 -4425);
FORCEPROP 1 LAST TOLERANCE 1%
J 2
(-2495 -4525);
DISPLAY 0.617021 (-2495 -4525);
PAINT SKYBLUE (-2495 -4525);
FORCEPROP 1 LAST PACK_TYPE 0402
J 2
(-2490 -4725);
DISPLAY 0.617021 (-2490 -4725);
PAINT SKYBLUE (-2490 -4725);
FORCEPROP 1 LAST WATTAGE 1/16W
J 2
(-2490 -4575);
DISPLAY 0.617021 (-2490 -4575);
PAINT SKYBLUE (-2490 -4575);
FORCEPROP 0 LAST GROUP AST2500
J 0
(-2697 -4840);
DISPLAY 0.638298 (-2697 -4840);
PAINT BROWN (-2697 -4840);
DISPLAY BOTH (-2697 -4840);
FORCEPROP 2 LAST SEC 1
J 0
(-2500 -4325);
DISPLAY 0.680851 (-2500 -4325);
PAINT MONO (-2500 -4325);
DISPLAY INVISIBLE (-2500 -4325);
FORCEPROP 2 LAST SEC_TYPE 0402
J 0
(-2500 -4325);
DISPLAY 1.021277 (-2500 -4325);
PAINT ORANGE (-2500 -4325);
DISPLAY INVISIBLE (-2500 -4325);
FORCEPROP 2 LAST CDS_LIB mstr_discrete
J 0
(-2450 -4550);
PAINT MONO (-2450 -4550);
DISPLAY INVISIBLE (-2450 -4550);
FORCEPROP 2 LAST BOM_COST PROC_SIDEBAND
J 2
(-2450 -4550);
PAINT MONO (-2450 -4550);
DISPLAY INVISIBLE (-2450 -4550);
FORCEPROP 2 LAST ROOM PROC_SIDEBAND
J 2
(-2475 -4775);
PAINT ORANGE (-2475 -4775);
DISPLAY INVISIBLE (-2475 -4775);
FORCEPROP 1 LAST PATH I140
J 2
(-2500 -4375);
DISPLAY 0.978723 (-2500 -4375);
PAINT WHITE (-2500 -4375);
DISPLAY INVISIBLE (-2500 -4375);
FORCEADD RES..2
R 2
(-2100 -4550);
FORCEPROP 1 LAST PART_NUMBER G21796-009
J 2
(-2140 -4675);
DISPLAY 0.617021 (-2140 -4675);
PAINT BLUE (-2140 -4675);
FORCEPROP 1 LAST VALUE 150.0
J 2
(-2145 -4475);
DISPLAY 0.617021 (-2145 -4475);
PAINT SKYBLUE (-2145 -4475);
FORCEPROP 1 LAST LOCATION R25W125
J 2
(-2145 -4425);
DISPLAY 0.617021 (-2145 -4425);
PAINT AQUA (-2145 -4425);
FORCEPROP 1 LAST MATERIAL CHIP
J 2
(-2140 -4625);
DISPLAY 0.617021 (-2140 -4625);
PAINT SKYBLUE (-2140 -4625);
FORCEPROP 1 LAST TOLERANCE 1%
J 2
(-2145 -4525);
DISPLAY 0.617021 (-2145 -4525);
PAINT SKYBLUE (-2145 -4525);
FORCEPROP 1 LASTPIN (-2100 -4650) $PN 2
J 2
(-2105 -4640);
DISPLAY 0.638298 (-2105 -4640);
PAINT ORANGE (-2105 -4640);
FORCEPROP 1 LAST PACK_TYPE 0402
J 2
(-2140 -4725);
DISPLAY 0.617021 (-2140 -4725);
PAINT SKYBLUE (-2140 -4725);
FORCEPROP 1 LASTPIN (-2100 -4450) $PN 1
J 2
(-2105 -4488);
DISPLAY 0.638298 (-2105 -4488);
PAINT ORANGE (-2105 -4488);
FORCEPROP 0 LAST GROUP AST2500
J 0
(-2347 -4765);
DISPLAY 0.638298 (-2347 -4765);
PAINT BROWN (-2347 -4765);
DISPLAY BOTH (-2347 -4765);
FORCEPROP 1 LAST WATTAGE 1/16W
J 2
(-2140 -4575);
DISPLAY 0.617021 (-2140 -4575);
PAINT SKYBLUE (-2140 -4575);
FORCEPROP 2 LAST SEC 1
J 0
(-2150 -4325);
DISPLAY 0.680851 (-2150 -4325);
PAINT MONO (-2150 -4325);
DISPLAY INVISIBLE (-2150 -4325);
FORCEPROP 2 LAST SEC_TYPE 0402
J 0
(-2150 -4325);
DISPLAY 1.021277 (-2150 -4325);
PAINT ORANGE (-2150 -4325);
DISPLAY INVISIBLE (-2150 -4325);
FORCEPROP 2 LAST CDS_LIB mstr_discrete
J 0
(-2100 -4550);
PAINT MONO (-2100 -4550);
DISPLAY INVISIBLE (-2100 -4550);
FORCEPROP 2 LAST BOM_COST PROC_SIDEBAND
J 2
(-2100 -4550);
PAINT MONO (-2100 -4550);
DISPLAY INVISIBLE (-2100 -4550);
FORCEPROP 2 LAST ROOM PROC_SIDEBAND
J 2
(-2125 -4775);
PAINT ORANGE (-2125 -4775);
DISPLAY INVISIBLE (-2125 -4775);
FORCEPROP 1 LAST PATH I141
J 2
(-2150 -4375);
DISPLAY 0.978723 (-2150 -4375);
PAINT WHITE (-2150 -4375);
DISPLAY INVISIBLE (-2150 -4375);
FORCEADD GND..1
(-2800 -4800);
FORCEPROP 3 LASTPIN (-2800 -4750) SIG_NAME GND\g
J 0
(-2790 -4740);
DISPLAY 0.659574 (-2790 -4740);
PAINT MONO (-2790 -4740);
DISPLAY INVISIBLE (-2790 -4740);
FORCEPROP 1 LAST HDL_POWER GND
J 0
(-2841 -4609);
DISPLAY 0.872340 (-2841 -4609);
PAINT GREEN (-2841 -4609);
DISPLAY INVISIBLE (-2841 -4609);
FORCEPROP 1 LAST BODY_TYPE PLUMBING
J 0
(-2861 -4827);
DISPLAY 0.340426 (-2861 -4827);
PAINT GREEN (-2861 -4827);
DISPLAY INVISIBLE (-2861 -4827);
FORCEPROP 1 LAST SIZE 1B
J 0
(-2766 -4809);
DISPLAY 0.872340 (-2766 -4809);
PAINT AQUA (-2766 -4809);
DISPLAY INVISIBLE (-2766 -4809);
FORCEPROP 1 LAST VOLTAGE 0.0V
J 0
(-2861 -4827);
DISPLAY 0.340426 (-2861 -4827);
PAINT SKYBLUE (-2861 -4827);
DISPLAY INVISIBLE (-2861 -4827);
FORCEPROP 2 LAST CDS_LIB mstr_symbols
J 0
(-2847 -4753);
PAINT ORANGE (-2847 -4753);
DISPLAY INVISIBLE (-2847 -4753);
FORCEPROP 1 LAST PATH I142
J 0
(-2725 -4800);
DISPLAY 0.872340 (-2725 -4800);
PAINT AQUA (-2725 -4800);
DISPLAY INVISIBLE (-2725 -4800);
FORCEADD GND..1
(-2450 -4800);
FORCEPROP 3 LASTPIN (-2450 -4750) SIG_NAME GND\g
J 0
(-2440 -4740);
DISPLAY 0.659574 (-2440 -4740);
PAINT MONO (-2440 -4740);
DISPLAY INVISIBLE (-2440 -4740);
FORCEPROP 2 LAST CDS_LIB mstr_symbols
J 0
(-2450 -4800);
PAINT MONO (-2450 -4800);
DISPLAY INVISIBLE (-2450 -4800);
FORCEPROP 1 LAST HDL_POWER GND
J 0
(-2491 -4609);
DISPLAY 0.872340 (-2491 -4609);
PAINT GREEN (-2491 -4609);
DISPLAY INVISIBLE (-2491 -4609);
FORCEPROP 1 LAST BODY_TYPE PLUMBING
J 0
(-2511 -4827);
DISPLAY 0.340426 (-2511 -4827);
PAINT GREEN (-2511 -4827);
DISPLAY INVISIBLE (-2511 -4827);
FORCEPROP 1 LAST SIZE 1B
J 0
(-2416 -4809);
DISPLAY 0.872340 (-2416 -4809);
PAINT AQUA (-2416 -4809);
DISPLAY INVISIBLE (-2416 -4809);
FORCEPROP 1 LAST VOLTAGE 0.0V
J 0
(-2511 -4827);
DISPLAY 0.340426 (-2511 -4827);
PAINT SKYBLUE (-2511 -4827);
DISPLAY INVISIBLE (-2511 -4827);
FORCEPROP 1 LAST PATH I143
J 0
(-2375 -4800);
DISPLAY 0.872340 (-2375 -4800);
PAINT AQUA (-2375 -4800);
DISPLAY INVISIBLE (-2375 -4800);
FORCEADD GND..1
(-2100 -4800);
FORCEPROP 3 LASTPIN (-2100 -4750) SIG_NAME GND\g
J 0
(-2090 -4740);
DISPLAY 0.659574 (-2090 -4740);
PAINT MONO (-2090 -4740);
DISPLAY INVISIBLE (-2090 -4740);
FORCEPROP 2 LAST CDS_LIB mstr_symbols
J 0
(-2100 -4800);
PAINT MONO (-2100 -4800);
DISPLAY INVISIBLE (-2100 -4800);
FORCEPROP 1 LAST HDL_POWER GND
J 0
(-2141 -4609);
DISPLAY 0.872340 (-2141 -4609);
PAINT GREEN (-2141 -4609);
DISPLAY INVISIBLE (-2141 -4609);
FORCEPROP 1 LAST BODY_TYPE PLUMBING
J 0
(-2161 -4827);
DISPLAY 0.340426 (-2161 -4827);
PAINT GREEN (-2161 -4827);
DISPLAY INVISIBLE (-2161 -4827);
FORCEPROP 1 LAST SIZE 1B
J 0
(-2066 -4809);
DISPLAY 0.872340 (-2066 -4809);
PAINT AQUA (-2066 -4809);
DISPLAY INVISIBLE (-2066 -4809);
FORCEPROP 1 LAST VOLTAGE 0.0V
J 0
(-2161 -4827);
DISPLAY 0.340426 (-2161 -4827);
PAINT SKYBLUE (-2161 -4827);
DISPLAY INVISIBLE (-2161 -4827);
FORCEPROP 1 LAST PATH I144
J 0
(-2025 -4800);
DISPLAY 0.872340 (-2025 -4800);
PAINT AQUA (-2025 -4800);
DISPLAY INVISIBLE (-2025 -4800);
FORCEADD OFFPAGE..1
(-7350 -1750);
FORCEPROP 2 LAST $XR2 158 
J 0
(-7872 -1750);
DISPLAY 0.638298 (-7872 -1750);
PAINT MONO (-7872 -1750);
FORCEPROP 2 LAST $XR1 120 
J 0
(-7752 -1750);
DISPLAY 0.638298 (-7752 -1750);
PAINT MONO (-7752 -1750);
FORCEPROP 2 LAST $XR0 190 
J 0
(-7632 -1750);
DISPLAY 0.638298 (-7632 -1750);
PAINT MONO (-7632 -1750);
FORCEPROP 2 LAST CDS_LIB mstr_standard
J 0
(-7350 -1750);
PAINT MONO (-7350 -1750);
DISPLAY INVISIBLE (-7350 -1750);
FORCEPROP 2 LAST PATH I146
J 0
(-7300 -1675);
DISPLAY 1.021277 (-7300 -1675);
PAINT ORANGE (-7300 -1675);
DISPLAY INVISIBLE (-7300 -1675);
FORCEPROP 1 LAST COMMENT_BODY TRUE
J 0
(-7225 -1850);
DISPLAY 0.872340 (-7225 -1850);
PAINT GREEN (-7225 -1850);
DISPLAY INVISIBLE (-7225 -1850);
FORCEPROP 1 LAST OFFPAGE TRUE
J 0
(-7025 -1875);
DISPLAY 0.872340 (-7025 -1875);
PAINT GREEN (-7025 -1875);
DISPLAY INVISIBLE (-7025 -1875);
FORCEPROP 2 LAST ROOM BMC
J 0
(-7600 -1675);
DISPLAY 1.361702 (-7600 -1675);
PAINT ORANGE (-7600 -1675);
DISPLAY INVISIBLE (-7600 -1675);
FORCEPROP 2 LAST BOM_COST SM_CONTROLLER
J 0
(-6900 -1700);
PAINT MONO (-6900 -1700);
DISPLAY INVISIBLE (-6900 -1700);
FORCEADD OFFPAGE..1
(-7350 -1700);
FORCEPROP 2 LAST $XR2 158 
J 0
(-7872 -1700);
DISPLAY 0.638298 (-7872 -1700);
PAINT MONO (-7872 -1700);
FORCEPROP 2 LAST $XR1 120 
J 0
(-7752 -1700);
DISPLAY 0.638298 (-7752 -1700);
PAINT MONO (-7752 -1700);
FORCEPROP 2 LAST $XR0 190 
J 0
(-7632 -1700);
DISPLAY 0.638298 (-7632 -1700);
PAINT MONO (-7632 -1700);
FORCEPROP 2 LAST BOM_COST SM_CONTROLLER
J 0
(-6900 -1650);
PAINT MONO (-6900 -1650);
DISPLAY INVISIBLE (-6900 -1650);
FORCEPROP 2 LAST ROOM BMC
J 0
(-7600 -1625);
DISPLAY 1.361702 (-7600 -1625);
PAINT ORANGE (-7600 -1625);
DISPLAY INVISIBLE (-7600 -1625);
FORCEPROP 1 LAST OFFPAGE TRUE
J 0
(-7025 -1825);
DISPLAY 0.872340 (-7025 -1825);
PAINT GREEN (-7025 -1825);
DISPLAY INVISIBLE (-7025 -1825);
FORCEPROP 1 LAST COMMENT_BODY TRUE
J 0
(-7225 -1800);
DISPLAY 0.872340 (-7225 -1800);
PAINT GREEN (-7225 -1800);
DISPLAY INVISIBLE (-7225 -1800);
FORCEPROP 2 LAST PATH I147
J 0
(-7300 -1625);
DISPLAY 1.021277 (-7300 -1625);
PAINT ORANGE (-7300 -1625);
DISPLAY INVISIBLE (-7300 -1625);
FORCEPROP 2 LAST CDS_LIB mstr_standard
J 0
(-7350 -1700);
PAINT MONO (-7350 -1700);
DISPLAY INVISIBLE (-7350 -1700);
FORCEADD RES..1
(-6700 -4300);
FORCEPROP 1 LAST PACK_TYPE 0402
J 0
(-6450 -4450);
DISPLAY 0.617021 (-6450 -4450);
PAINT SKYBLUE (-6450 -4450);
FORCEPROP 1 LAST TOLERANCE 5%
J 0
(-6700 -4400);
DISPLAY 0.617021 (-6700 -4400);
PAINT SKYBLUE (-6700 -4400);
FORCEPROP 1 LAST MATERIAL EMPTY
J 0
(-6700 -4450);
DISPLAY 0.617021 (-6700 -4450);
PAINT RED (-6700 -4450);
FORCEPROP 1 LAST WATTAGE 1/16W
J 2
(-6725 -4450);
DISPLAY 0.617021 (-6725 -4450);
PAINT SKYBLUE (-6725 -4450);
FORCEPROP 1 LAST VALUE 0.0
J 2
(-6725 -4400);
DISPLAY 0.617021 (-6725 -4400);
PAINT SKYBLUE (-6725 -4400);
FORCEPROP 1 LASTPIN (-6800 -4300) $PN 1
J 0
(-6788 -4288);
DISPLAY 0.787234 (-6788 -4288);
PAINT ORANGE (-6788 -4288);
FORCEPROP 1 LASTPIN (-6600 -4300) $PN 2
J 0
(-6638 -4288);
DISPLAY 0.787234 (-6638 -4288);
PAINT ORANGE (-6638 -4288);
FORCEPROP 1 LAST LOCATION R25W140
J 0
(-6900 -4200);
DISPLAY 0.617021 (-6900 -4200);
PAINT AQUA (-6900 -4200);
FORCEPROP 1 LAST PART_NUMBER G21497-005
J 0
(-6700 -4200);
DISPLAY 0.617021 (-6700 -4200);
PAINT BLUE (-6700 -4200);
FORCEPROP 2 LAST CDS_LIB mstr_discrete
J 0
(-6700 -4300);
PAINT MONO (-6700 -4300);
DISPLAY INVISIBLE (-6700 -4300);
FORCEPROP 0 LAST ROOM NV_DIMM
J 0
(-6750 -4100);
DISPLAY 1.021277 (-6750 -4100);
PAINT ORANGE (-6750 -4100);
DISPLAY INVISIBLE (-6750 -4100);
FORCEPROP 0 LAST BOM_COST MEM_NV
J 0
(-6750 -4000);
DISPLAY 1.021277 (-6750 -4000);
PAINT ORANGE (-6750 -4000);
DISPLAY INVISIBLE (-6750 -4000);
FORCEPROP 1 LAST PATH I148
J 0
(-6750 -4150);
DISPLAY 0.978723 (-6750 -4150);
PAINT WHITE (-6750 -4150);
DISPLAY INVISIBLE (-6750 -4150);
FORCEPROP 2 LAST SEC_TYPE 0402
J 0
(-6750 -4100);
DISPLAY 1.021277 (-6750 -4100);
PAINT ORANGE (-6750 -4100);
DISPLAY INVISIBLE (-6750 -4100);
FORCEPROP 2 LAST SEC 1
J 0
(-6750 -4100);
PAINT MONO (-6750 -4100);
DISPLAY INVISIBLE (-6750 -4100);
FORCEPROP 2 LAST CDS_LOCATION R25W140
J 0
(-6750 -4250);
DISPLAY 0.617021 (-6750 -4250);
PAINT AQUA (-6750 -4250);
DISPLAY INVISIBLE (-6750 -4250);
FORCEADD OFFPAGE..4
(-2350 -3150);
FORCEPROP 2 LAST $XR0 150 
J 0
(-2164 -3150);
DISPLAY 0.638298 (-2164 -3150);
PAINT MONO (-2164 -3150);
FORCEPROP 1 LAST OFFPAGE TRUE
J 0
(-2025 -3275);
DISPLAY 0.872340 (-2025 -3275);
PAINT GREEN (-2025 -3275);
DISPLAY INVISIBLE (-2025 -3275);
FORCEPROP 1 LAST COMMENT_BODY TRUE
J 0
(-2375 -3250);
DISPLAY 0.872340 (-2375 -3250);
PAINT GREEN (-2375 -3250);
DISPLAY INVISIBLE (-2375 -3250);
FORCEPROP 2 LAST PATH I149
J 0
(-2175 -3075);
DISPLAY 1.021277 (-2175 -3075);
PAINT ORANGE (-2175 -3075);
DISPLAY INVISIBLE (-2175 -3075);
FORCEPROP 2 LAST CDS_LIB mstr_standard
J 0
(-2350 -3150);
PAINT MONO (-2350 -3150);
DISPLAY INVISIBLE (-2350 -3150);
FORCEADD 18KR2F-GP..1
(-2400 -3525);
FORCEPROP 2 LAST PACK_SIZE 0402
J 0
(-2375 -3675);
DISPLAY 0.638298 (-2375 -3675);
PAINT GREEN (-2375 -3675);
FORCEPROP 2 LASTPIN (-2400 -3400) $PN 1
R 1
J 0
(-2410 -3390);
DISPLAY 0.808511 (-2410 -3390);
PAINT ORANGE (-2410 -3390);
FORCEPROP 2 LASTPIN (-2400 -3650) $PN 2
R 1
J 2
(-2410 -3660);
DISPLAY 0.808511 (-2410 -3660);
PAINT ORANGE (-2410 -3660);
FORCEPROP 2 LAST RATED 1/16W
J 0
(-2375 -3625);
DISPLAY 0.638298 (-2375 -3625);
PAINT GREEN (-2375 -3625);
FORCEPROP 2 LAST TOLERANCE 1%
J 0
(-2375 -3575);
DISPLAY 0.638298 (-2375 -3575);
PAINT GREEN (-2375 -3575);
FORCEPROP 1 LAST VALUE 18KR2F-GP
J 0
(-2375 -3475);
DISPLAY 0.617021 (-2375 -3475);
PAINT GREEN (-2375 -3475);
FORCEPROP 1 LAST LOCATION R25W58
J 0
(-2375 -3425);
DISPLAY 0.617021 (-2375 -3425);
PAINT GREEN (-2375 -3425);
FORCEPROP 2 LAST ATTRIBUTE 18KOHM
J 0
(-2375 -3525);
DISPLAY 0.638298 (-2375 -3525);
PAINT GREEN (-2375 -3525);
FORCEPROP 1 LAST CDS_LMAN_SYM_OUTLINE -50,75,50,-75
J 0
(-2400 -3525);
DISPLAY 0.468085 (-2400 -3525);
PAINT GREEN (-2400 -3525);
DISPLAY INVISIBLE (-2400 -3525);
FORCEPROP 1 LAST PATH I150
J 0
(-2400 -3525);
DISPLAY 0.617021 (-2400 -3525);
PAINT GREEN (-2400 -3525);
DISPLAY INVISIBLE (-2400 -3525);
FORCEPROP 2 LAST CDS_LIB w_hdl
J 0
(-2400 -3525);
DISPLAY INVISIBLE (-2400 -3525);
FORCEPROP 1 LAST PART_NUMBER 64.18025.6DL
J 0
(-2400 -3525);
DISPLAY 0.617021 (-2400 -3525);
PAINT GREEN (-2400 -3525);
DISPLAY INVISIBLE (-2400 -3525);
FORCEPROP 2 LAST SEC_TYPE RCL_GP
J 0
(-2375 -3375);
DISPLAY 1.021277 (-2375 -3375);
PAINT ORANGE (-2375 -3375);
DISPLAY INVISIBLE (-2375 -3375);
FORCEPROP 2 LAST SEC 1
J 0
(-2375 -3375);
DISPLAY 0.680851 (-2375 -3375);
PAINT MONO (-2375 -3375);
DISPLAY INVISIBLE (-2375 -3375);
FORCEPROP 1 LAST PACK_TYPE RCL_GP
J 0
(-2400 -3525);
DISPLAY 0.617021 (-2400 -3525);
PAINT GREEN (-2400 -3525);
DISPLAY INVISIBLE (-2400 -3525);
FORCEADD RES..1
(-6700 -4050);
FORCEPROP 1 LAST LOCATION R25W182
J 0
(-6800 -3750);
DISPLAY 0.617021 (-6800 -3750);
PAINT AQUA (-6800 -3750);
FORCEPROP 1 LASTPIN (-6800 -4050) $PN 1
J 0
(-6788 -4038);
DISPLAY 0.787234 (-6788 -4038);
PAINT ORANGE (-6788 -4038);
FORCEPROP 1 LAST PACK_TYPE 0402
J 0
(-6650 -3850);
DISPLAY 0.617021 (-6650 -3850);
PAINT SKYBLUE (-6650 -3850);
FORCEPROP 1 LAST TOLERANCE 5%
J 0
(-6775 -3900);
DISPLAY 0.617021 (-6775 -3900);
PAINT SKYBLUE (-6775 -3900);
FORCEPROP 1 LAST WATTAGE 1/16W
J 0
(-6800 -3950);
DISPLAY 0.617021 (-6800 -3950);
PAINT SKYBLUE (-6800 -3950);
FORCEPROP 1 LASTPIN (-6600 -4050) $PN 2
J 0
(-6638 -4038);
DISPLAY 0.787234 (-6638 -4038);
PAINT ORANGE (-6638 -4038);
FORCEPROP 1 LAST VALUE 0.0
J 2
(-6725 -3850);
DISPLAY 0.617021 (-6725 -3850);
PAINT SKYBLUE (-6725 -3850);
FORCEPROP 1 LAST PART_NUMBER G21497-005
J 0
(-6800 -3800);
DISPLAY 0.617021 (-6800 -3800);
PAINT BLUE (-6800 -3800);
FORCEPROP 1 LAST MATERIAL CHIP
J 0
(-6650 -3900);
DISPLAY 0.617021 (-6650 -3900);
PAINT SKYBLUE (-6650 -3900);
FORCEPROP 0 LAST POP NOPOP
J 0
(-6775 -4000);
DISPLAY 0.638298 (-6775 -4000);
PAINT RED (-6775 -4000);
FORCEPROP 1 LAST PATH I151
J 0
(-6750 -3900);
DISPLAY 0.978723 (-6750 -3900);
PAINT WHITE (-6750 -3900);
DISPLAY INVISIBLE (-6750 -3900);
FORCEPROP 0 LAST CDS_SEC 1
J 0
(-6850 -4000);
DISPLAY INVISIBLE (-6850 -4000);
FORCEPROP 2 LAST SEC 1
J 0
(-6750 -3850);
DISPLAY 0.680851 (-6750 -3850);
PAINT MONO (-6750 -3850);
DISPLAY INVISIBLE (-6750 -3850);
FORCEPROP 2 LAST SEC_TYPE 0402
J 0
(-6750 -3850);
DISPLAY 1.021277 (-6750 -3850);
PAINT ORANGE (-6750 -3850);
DISPLAY INVISIBLE (-6750 -3850);
FORCEPROP 0 LAST ROOM DEBUG
J 0
(-6750 -3850);
DISPLAY 1.021277 (-6750 -3850);
PAINT ORANGE (-6750 -3850);
DISPLAY INVISIBLE (-6750 -3850);
FORCEPROP 2 LAST CDS_LIB mstr_discrete
J 0
(-6700 -4050);
PAINT MONO (-6700 -4050);
DISPLAY INVISIBLE (-6700 -4050);
FORCEPROP 0 LAST CDS_LOCATION R25W182
J 0
(-6850 -4000);
DISPLAY INVISIBLE (-6850 -4000);
FORCEADD OFFPAGE..1
(-7600 -4050);
FORCEPROP 2 LAST $XR1 190 
J 0
(-7972 -4050);
DISPLAY 0.638298 (-7972 -4050);
PAINT MONO (-7972 -4050);
FORCEPROP 2 LAST $XR0 111 
J 0
(-7852 -4050);
DISPLAY 0.638298 (-7852 -4050);
PAINT MONO (-7852 -4050);
FORCEPROP 2 LAST PATH I152
J 0
(-7850 -4000);
DISPLAY 1.021277 (-7850 -4000);
PAINT ORANGE (-7850 -4000);
DISPLAY INVISIBLE (-7850 -4000);
FORCEPROP 2 LAST BOM_COST SM_CONTROLLER
J 0
(-7150 -4000);
PAINT MONO (-7150 -4000);
DISPLAY INVISIBLE (-7150 -4000);
FORCEPROP 2 LAST ROOM BMC
J 0
(-7850 -3975);
DISPLAY 1.361702 (-7850 -3975);
PAINT ORANGE (-7850 -3975);
DISPLAY INVISIBLE (-7850 -3975);
FORCEPROP 2 LAST CDS_LIB mstr_standard
J 0
(-7600 -4050);
PAINT ORANGE (-7600 -4050);
DISPLAY INVISIBLE (-7600 -4050);
FORCEPROP 1 LAST OFFPAGE TRUE
J 0
(-7275 -4175);
DISPLAY 0.872340 (-7275 -4175);
PAINT GREEN (-7275 -4175);
DISPLAY INVISIBLE (-7275 -4175);
FORCEPROP 1 LAST COMMENT_BODY TRUE
J 0
(-7475 -4150);
DISPLAY 0.872340 (-7475 -4150);
PAINT GREEN (-7475 -4150);
DISPLAY INVISIBLE (-7475 -4150);
FORCEADD OFFPAGE..5
(-7350 -3350);
FORCEPROP 2 LAST $XR0 255 
J 0
(-7605 -3350);
DISPLAY 0.638298 (-7605 -3350);
PAINT MONO (-7605 -3350);
FORCEPROP 2 LAST PATH I153
J 0
(-7625 -3300);
DISPLAY 1.021277 (-7625 -3300);
PAINT ORANGE (-7625 -3300);
DISPLAY INVISIBLE (-7625 -3300);
FORCEPROP 2 LAST CDS_LIB mstr_standard
J 0
(-7350 -3350);
PAINT ORANGE (-7350 -3350);
DISPLAY INVISIBLE (-7350 -3350);
FORCEPROP 1 LAST OFFPAGE TRUE
J 0
(-7025 -3475);
DISPLAY 0.872340 (-7025 -3475);
PAINT GREEN (-7025 -3475);
DISPLAY INVISIBLE (-7025 -3475);
FORCEPROP 1 LAST COMMENT_BODY TRUE
J 0
(-7250 -3425);
DISPLAY 0.872340 (-7250 -3425);
PAINT GREEN (-7250 -3425);
DISPLAY INVISIBLE (-7250 -3425);
FORCEADD OFFPAGE..5
(-7350 -2050);
FORCEPROP 2 LAST $XR0 159 
J 0
(-7635 -2050);
DISPLAY 0.638298 (-7635 -2050);
PAINT MONO (-7635 -2050);
FORCEPROP 2 LAST PATH I28
J 0
(-7300 -1975);
DISPLAY 1.021277 (-7300 -1975);
PAINT ORANGE (-7300 -1975);
DISPLAY INVISIBLE (-7300 -1975);
FORCEPROP 2 LAST CDS_LIB mstr_standard
J 0
(-7350 -2050);
PAINT MONO (-7350 -2050);
DISPLAY INVISIBLE (-7350 -2050);
FORCEPROP 1 LAST OFFPAGE TRUE
J 0
(-7025 -2175);
DISPLAY 0.872340 (-7025 -2175);
PAINT GREEN (-7025 -2175);
DISPLAY INVISIBLE (-7025 -2175);
FORCEPROP 1 LAST COMMENT_BODY TRUE
J 0
(-7250 -2125);
DISPLAY 0.872340 (-7250 -2125);
PAINT GREEN (-7250 -2125);
DISPLAY INVISIBLE (-7250 -2125);
FORCEADD OFFPAGE..3
R 2
(-7350 -2000);
FORCEPROP 2 LAST $XR0 159 
J 0
(-7630 -2000);
DISPLAY 0.638298 (-7630 -2000);
PAINT MONO (-7630 -2000);
FORCEPROP 2 LAST CDS_LIB mstr_standard
J 0
(-7350 -2000);
PAINT MONO (-7350 -2000);
DISPLAY INVISIBLE (-7350 -2000);
FORCEPROP 2 LAST PATH I29
J 0
(-7300 -1925);
DISPLAY 1.021277 (-7300 -1925);
PAINT ORANGE (-7300 -1925);
DISPLAY INVISIBLE (-7300 -1925);
FORCEPROP 2 LAST ROOM BMC
J 2
(-7825 -1950);
PAINT MONO (-7825 -1950);
DISPLAY INVISIBLE (-7825 -1950);
FORCEPROP 2 LAST BOM_COST SM_CONTROLLER
J 2
(-7825 -1950);
PAINT MONO (-7825 -1950);
DISPLAY INVISIBLE (-7825 -1950);
FORCEPROP 1 LAST OFFPAGE TRUE
J 2
(-7675 -2125);
PAINT GREEN (-7675 -2125);
DISPLAY INVISIBLE (-7675 -2125);
FORCEPROP 1 LAST COMMENT_BODY TRUE
J 2
(-7300 -2100);
DISPLAY 1.170213 (-7300 -2100);
PAINT GREEN (-7300 -2100);
DISPLAY INVISIBLE (-7300 -2100);
FORCEADD OFFPAGE..5
(-7350 -2650);
FORCEPROP 2 LAST $XR0 159 
J 0
(-7635 -2650);
DISPLAY 0.638298 (-7635 -2650);
PAINT MONO (-7635 -2650);
FORCEPROP 2 LAST PATH I32
J 0
(-7300 -2575);
DISPLAY 1.021277 (-7300 -2575);
PAINT ORANGE (-7300 -2575);
DISPLAY INVISIBLE (-7300 -2575);
FORCEPROP 2 LAST CDS_LIB mstr_standard
J 0
(-7350 -2650);
PAINT MONO (-7350 -2650);
DISPLAY INVISIBLE (-7350 -2650);
FORCEPROP 1 LAST OFFPAGE TRUE
J 0
(-7025 -2775);
DISPLAY 0.872340 (-7025 -2775);
PAINT GREEN (-7025 -2775);
DISPLAY INVISIBLE (-7025 -2775);
FORCEPROP 1 LAST COMMENT_BODY TRUE
J 0
(-7250 -2725);
DISPLAY 0.872340 (-7250 -2725);
PAINT GREEN (-7250 -2725);
DISPLAY INVISIBLE (-7250 -2725);
FORCEADD OFFPAGE..3
R 2
(-7350 -2600);
FORCEPROP 2 LAST $XR0 159 
J 0
(-7630 -2600);
DISPLAY 0.638298 (-7630 -2600);
PAINT MONO (-7630 -2600);
FORCEPROP 1 LAST COMMENT_BODY TRUE
J 2
(-7300 -2700);
DISPLAY 1.170213 (-7300 -2700);
PAINT GREEN (-7300 -2700);
DISPLAY INVISIBLE (-7300 -2700);
FORCEPROP 1 LAST OFFPAGE TRUE
J 2
(-7675 -2725);
PAINT GREEN (-7675 -2725);
DISPLAY INVISIBLE (-7675 -2725);
FORCEPROP 2 LAST ROOM BMC
J 2
(-7825 -2550);
PAINT MONO (-7825 -2550);
DISPLAY INVISIBLE (-7825 -2550);
FORCEPROP 2 LAST BOM_COST SM_CONTROLLER
J 2
(-7825 -2550);
PAINT MONO (-7825 -2550);
DISPLAY INVISIBLE (-7825 -2550);
FORCEPROP 2 LAST PATH I37
J 0
(-7300 -2525);
DISPLAY 1.021277 (-7300 -2525);
PAINT ORANGE (-7300 -2525);
DISPLAY INVISIBLE (-7300 -2525);
FORCEPROP 2 LAST CDS_LIB mstr_standard
J 0
(-7350 -2600);
PAINT MONO (-7350 -2600);
DISPLAY INVISIBLE (-7350 -2600);
FORCEADD OFFPAGE..1
(-7350 -3300);
FORCEPROP 2 LAST $XR2 118 
J 0
(-7872 -3300);
DISPLAY 0.638298 (-7872 -3300);
PAINT MONO (-7872 -3300);
FORCEPROP 2 LAST $XR1 191 
J 0
(-7752 -3300);
DISPLAY 0.638298 (-7752 -3300);
PAINT MONO (-7752 -3300);
FORCEPROP 2 LAST $XR0 133 
J 0
(-7632 -3300);
DISPLAY 0.638298 (-7632 -3300);
PAINT MONO (-7632 -3300);
FORCEPROP 2 LAST CDS_LIB mstr_standard
J 0
(-7350 -3300);
PAINT MONO (-7350 -3300);
DISPLAY INVISIBLE (-7350 -3300);
FORCEPROP 2 LAST PATH I44
J 0
(-7300 -3225);
DISPLAY 1.021277 (-7300 -3225);
PAINT ORANGE (-7300 -3225);
DISPLAY INVISIBLE (-7300 -3225);
FORCEPROP 2 LAST BOM_COST SM_CONTROLLER
J 0
(-6900 -3250);
PAINT MONO (-6900 -3250);
DISPLAY INVISIBLE (-6900 -3250);
FORCEPROP 2 LAST ROOM BMC
J 0
(-7600 -3225);
DISPLAY 1.361702 (-7600 -3225);
PAINT ORANGE (-7600 -3225);
DISPLAY INVISIBLE (-7600 -3225);
FORCEPROP 1 LAST OFFPAGE TRUE
J 0
(-7025 -3425);
DISPLAY 0.872340 (-7025 -3425);
PAINT GREEN (-7025 -3425);
DISPLAY INVISIBLE (-7025 -3425);
FORCEPROP 1 LAST COMMENT_BODY TRUE
J 0
(-7225 -3400);
DISPLAY 0.872340 (-7225 -3400);
PAINT GREEN (-7225 -3400);
DISPLAY INVISIBLE (-7225 -3400);
FORCEADD OFFPAGE..5
(-7350 -3550);
FORCEPROP 2 LAST $XR2 119 
J 0
(-7845 -3550);
DISPLAY 0.638298 (-7845 -3550);
PAINT MONO (-7845 -3550);
FORCEPROP 2 LAST $XR1 133 
J 0
(-7725 -3550);
DISPLAY 0.638298 (-7725 -3550);
PAINT MONO (-7725 -3550);
FORCEPROP 2 LAST $XR0 120 
J 0
(-7605 -3550);
DISPLAY 0.638298 (-7605 -3550);
PAINT MONO (-7605 -3550);
FORCEPROP 1 LAST COMMENT_BODY TRUE
J 0
(-7250 -3625);
DISPLAY 0.872340 (-7250 -3625);
PAINT GREEN (-7250 -3625);
DISPLAY INVISIBLE (-7250 -3625);
FORCEPROP 1 LAST OFFPAGE TRUE
J 0
(-7025 -3675);
DISPLAY 0.872340 (-7025 -3675);
PAINT GREEN (-7025 -3675);
DISPLAY INVISIBLE (-7025 -3675);
FORCEPROP 2 LAST PATH I47
J 0
(-7625 -3500);
DISPLAY 1.021277 (-7625 -3500);
PAINT ORANGE (-7625 -3500);
DISPLAY INVISIBLE (-7625 -3500);
FORCEPROP 2 LAST CDS_LIB mstr_standard
J 0
(-7350 -3550);
PAINT MONO (-7350 -3550);
DISPLAY INVISIBLE (-7350 -3550);
FORCEADD OFFPAGE..1
(-7350 -3600);
FORCEPROP 2 LAST $XR3 247 
J 0
(-7992 -3600);
DISPLAY 0.638298 (-7992 -3600);
PAINT MONO (-7992 -3600);
FORCEPROP 2 LAST $XR2 118 
J 0
(-7872 -3600);
DISPLAY 0.638298 (-7872 -3600);
PAINT MONO (-7872 -3600);
FORCEPROP 2 LAST $XR1 191 
J 0
(-7752 -3600);
DISPLAY 0.638298 (-7752 -3600);
PAINT MONO (-7752 -3600);
FORCEPROP 2 LAST $XR0 133 
J 0
(-7632 -3600);
DISPLAY 0.638298 (-7632 -3600);
PAINT MONO (-7632 -3600);
FORCEPROP 1 LAST COMMENT_BODY TRUE
J 0
(-7225 -3700);
DISPLAY 0.872340 (-7225 -3700);
PAINT GREEN (-7225 -3700);
DISPLAY INVISIBLE (-7225 -3700);
FORCEPROP 1 LAST OFFPAGE TRUE
J 0
(-7025 -3725);
DISPLAY 0.872340 (-7025 -3725);
PAINT GREEN (-7025 -3725);
DISPLAY INVISIBLE (-7025 -3725);
FORCEPROP 2 LAST PATH I48
J 0
(-7625 -3550);
DISPLAY 1.021277 (-7625 -3550);
PAINT ORANGE (-7625 -3550);
DISPLAY INVISIBLE (-7625 -3550);
FORCEPROP 2 LAST CDS_LIB mstr_standard
J 0
(-7350 -3600);
PAINT MONO (-7350 -3600);
DISPLAY INVISIBLE (-7350 -3600);
FORCEPROP 2 LAST ROOM BMC
J 0
(-7600 -3525);
DISPLAY 1.361702 (-7600 -3525);
PAINT ORANGE (-7600 -3525);
DISPLAY INVISIBLE (-7600 -3525);
FORCEPROP 2 LAST BOM_COST SM_CONTROLLER
J 0
(-6900 -3550);
PAINT MONO (-6900 -3550);
DISPLAY INVISIBLE (-6900 -3550);
FORCEADD OFFPAGE..1
(-7350 -3650);
FORCEPROP 2 LAST $XR2 119 
J 0
(-7842 -3650);
DISPLAY 0.638298 (-7842 -3650);
PAINT MONO (-7842 -3650);
FORCEPROP 2 LAST $XR1 94 
J 0
(-7722 -3650);
DISPLAY 0.638298 (-7722 -3650);
PAINT MONO (-7722 -3650);
FORCEPROP 2 LAST $XR0 223 
J 0
(-7632 -3650);
DISPLAY 0.638298 (-7632 -3650);
PAINT MONO (-7632 -3650);
FORCEPROP 1 LAST COMMENT_BODY TRUE
J 0
(-7225 -3750);
DISPLAY 0.872340 (-7225 -3750);
PAINT GREEN (-7225 -3750);
DISPLAY INVISIBLE (-7225 -3750);
FORCEPROP 1 LAST OFFPAGE TRUE
J 0
(-7025 -3775);
DISPLAY 0.872340 (-7025 -3775);
PAINT GREEN (-7025 -3775);
DISPLAY INVISIBLE (-7025 -3775);
FORCEPROP 2 LAST ROOM BMC
J 0
(-7600 -3575);
DISPLAY 1.361702 (-7600 -3575);
PAINT ORANGE (-7600 -3575);
DISPLAY INVISIBLE (-7600 -3575);
FORCEPROP 2 LAST BOM_COST SM_CONTROLLER
J 0
(-6900 -3600);
PAINT MONO (-6900 -3600);
DISPLAY INVISIBLE (-6900 -3600);
FORCEPROP 2 LAST CDS_LIB mstr_standard
J 0
(-7350 -3650);
PAINT ORANGE (-7350 -3650);
DISPLAY INVISIBLE (-7350 -3650);
FORCEPROP 2 LAST PATH I49
J 0
(-7600 -3600);
DISPLAY 1.021277 (-7600 -3600);
PAINT ORANGE (-7600 -3600);
DISPLAY INVISIBLE (-7600 -3600);
FORCEADD OFFPAGE..4
(-2350 -1900);
FORCEPROP 2 LAST $XR1 120 
J 0
(-2074 -1900);
DISPLAY 0.638298 (-2074 -1900);
PAINT MONO (-2074 -1900);
FORCEPROP 2 LAST $XR0 92 
J 0
(-2164 -1900);
DISPLAY 0.638298 (-2164 -1900);
PAINT MONO (-2164 -1900);
FORCEPROP 2 LAST PATH I50
J 0
(-2050 -1850);
DISPLAY 1.021277 (-2050 -1850);
PAINT ORANGE (-2050 -1850);
DISPLAY INVISIBLE (-2050 -1850);
FORCEPROP 2 LAST CDS_LIB mstr_standard
J 0
(-2350 -1900);
PAINT MONO (-2350 -1900);
DISPLAY INVISIBLE (-2350 -1900);
FORCEPROP 1 LAST OFFPAGE TRUE
J 0
(-2025 -2025);
DISPLAY 0.872340 (-2025 -2025);
PAINT GREEN (-2025 -2025);
DISPLAY INVISIBLE (-2025 -2025);
FORCEPROP 1 LAST COMMENT_BODY TRUE
J 0
(-2375 -2000);
DISPLAY 0.872340 (-2375 -2000);
PAINT GREEN (-2375 -2000);
DISPLAY INVISIBLE (-2375 -2000);
FORCEADD OFFPAGE..4
(-2350 -1850);
FORCEPROP 2 LAST $XR2 247 
J 0
(-1954 -1850);
DISPLAY 0.638298 (-1954 -1850);
PAINT MONO (-1954 -1850);
FORCEPROP 2 LAST $XR1 190 
J 0
(-2074 -1850);
DISPLAY 0.638298 (-2074 -1850);
PAINT MONO (-2074 -1850);
FORCEPROP 2 LAST $XR0 92 
J 0
(-2164 -1850);
DISPLAY 0.638298 (-2164 -1850);
PAINT MONO (-2164 -1850);
FORCEPROP 2 LAST CDS_LIB mstr_standard
J 0
(-2350 -1850);
PAINT ORANGE (-2350 -1850);
DISPLAY INVISIBLE (-2350 -1850);
FORCEPROP 2 LAST PATH I51
J 0
(-2050 -1800);
DISPLAY 1.021277 (-2050 -1800);
PAINT ORANGE (-2050 -1800);
DISPLAY INVISIBLE (-2050 -1800);
FORCEPROP 1 LAST OFFPAGE TRUE
J 0
(-2025 -1975);
DISPLAY 0.872340 (-2025 -1975);
PAINT GREEN (-2025 -1975);
DISPLAY INVISIBLE (-2025 -1975);
FORCEPROP 1 LAST COMMENT_BODY TRUE
J 0
(-2375 -1950);
DISPLAY 0.872340 (-2375 -1950);
PAINT GREEN (-2375 -1950);
DISPLAY INVISIBLE (-2375 -1950);
FORCEADD OFFPAGE..4
(-2350 -1750);
FORCEPROP 2 LAST $XR1 120 
J 0
(-2044 -1750);
DISPLAY 0.638298 (-2044 -1750);
PAINT MONO (-2044 -1750);
FORCEPROP 2 LAST $XR0 134 
J 0
(-2164 -1750);
DISPLAY 0.638298 (-2164 -1750);
PAINT MONO (-2164 -1750);
FORCEPROP 2 LAST CDS_LIB mstr_standard
J 0
(-2350 -1750);
PAINT ORANGE (-2350 -1750);
DISPLAY INVISIBLE (-2350 -1750);
FORCEPROP 2 LAST PATH I52
J 0
(-2025 -1700);
DISPLAY 1.021277 (-2025 -1700);
PAINT ORANGE (-2025 -1700);
DISPLAY INVISIBLE (-2025 -1700);
FORCEPROP 1 LAST OFFPAGE TRUE
J 0
(-2025 -1875);
DISPLAY 0.872340 (-2025 -1875);
PAINT GREEN (-2025 -1875);
DISPLAY INVISIBLE (-2025 -1875);
FORCEPROP 1 LAST COMMENT_BODY TRUE
J 0
(-2375 -1850);
DISPLAY 0.872340 (-2375 -1850);
PAINT GREEN (-2375 -1850);
DISPLAY INVISIBLE (-2375 -1850);
FORCEADD OFFPAGE..2
(-600 -2150);
FORCEPROP 2 LAST $XR0 190 
J 0
(-411 -2150);
DISPLAY 0.638298 (-411 -2150);
PAINT MONO (-411 -2150);
FORCEPROP 2 LAST PATH I53
J 0
(-400 -2100);
DISPLAY 1.021277 (-400 -2100);
PAINT ORANGE (-400 -2100);
DISPLAY INVISIBLE (-400 -2100);
FORCEPROP 2 LAST CDS_LIB mstr_standard
J 0
(-600 -2150);
PAINT MONO (-600 -2150);
DISPLAY INVISIBLE (-600 -2150);
FORCEPROP 1 LAST OFFPAGE TRUE
J 0
(-275 -2275);
DISPLAY 0.872340 (-275 -2275);
PAINT GREEN (-275 -2275);
DISPLAY INVISIBLE (-275 -2275);
FORCEPROP 1 LAST COMMENT_BODY TRUE
J 0
(-645 -2245);
DISPLAY 0.872340 (-645 -2245);
PAINT GREEN (-645 -2245);
DISPLAY INVISIBLE (-645 -2245);
FORCEADD OFFPAGE..2
(-600 -2050);
FORCEPROP 2 LAST $XR0 190 
J 0
(-411 -2050);
DISPLAY 0.638298 (-411 -2050);
PAINT MONO (-411 -2050);
FORCEPROP 2 LAST PATH I54
J 0
(-400 -2000);
DISPLAY 1.021277 (-400 -2000);
PAINT ORANGE (-400 -2000);
DISPLAY INVISIBLE (-400 -2000);
FORCEPROP 2 LAST CDS_LIB mstr_standard
J 0
(-600 -2050);
PAINT MONO (-600 -2050);
DISPLAY INVISIBLE (-600 -2050);
FORCEPROP 1 LAST OFFPAGE TRUE
J 0
(-275 -2175);
DISPLAY 0.872340 (-275 -2175);
PAINT GREEN (-275 -2175);
DISPLAY INVISIBLE (-275 -2175);
FORCEPROP 1 LAST COMMENT_BODY TRUE
J 0
(-645 -2145);
DISPLAY 0.872340 (-645 -2145);
PAINT GREEN (-645 -2145);
DISPLAY INVISIBLE (-645 -2145);
FORCEADD OFFPAGE..2
(-600 -2200);
FORCEPROP 2 LAST $XR0 190 
J 0
(-411 -2200);
DISPLAY 0.638298 (-411 -2200);
PAINT MONO (-411 -2200);
FORCEPROP 2 LAST PATH I55
J 0
(-400 -2150);
DISPLAY 1.021277 (-400 -2150);
PAINT ORANGE (-400 -2150);
DISPLAY INVISIBLE (-400 -2150);
FORCEPROP 2 LAST CDS_LIB mstr_standard
J 0
(-600 -2200);
PAINT MONO (-600 -2200);
DISPLAY INVISIBLE (-600 -2200);
FORCEPROP 1 LAST OFFPAGE TRUE
J 0
(-275 -2325);
DISPLAY 0.872340 (-275 -2325);
PAINT GREEN (-275 -2325);
DISPLAY INVISIBLE (-275 -2325);
FORCEPROP 1 LAST COMMENT_BODY TRUE
J 0
(-645 -2295);
DISPLAY 0.872340 (-645 -2295);
PAINT GREEN (-645 -2295);
DISPLAY INVISIBLE (-645 -2295);
FORCEADD OFFPAGE..4
(-600 -2000);
FORCEPROP 2 LAST $XR0 191 
J 0
(-414 -2000);
DISPLAY 0.638298 (-414 -2000);
PAINT MONO (-414 -2000);
FORCEPROP 1 LAST COMMENT_BODY TRUE
J 0
(-625 -2100);
DISPLAY 0.872340 (-625 -2100);
PAINT GREEN (-625 -2100);
DISPLAY INVISIBLE (-625 -2100);
FORCEPROP 1 LAST OFFPAGE TRUE
J 0
(-275 -2125);
DISPLAY 0.872340 (-275 -2125);
PAINT GREEN (-275 -2125);
DISPLAY INVISIBLE (-275 -2125);
FORCEPROP 2 LAST PATH I56
J 0
(-400 -1950);
DISPLAY 1.021277 (-400 -1950);
PAINT ORANGE (-400 -1950);
DISPLAY INVISIBLE (-400 -1950);
FORCEPROP 2 LAST CDS_LIB mstr_standard
J 0
(-600 -2000);
PAINT MONO (-600 -2000);
DISPLAY INVISIBLE (-600 -2000);
FORCEADD RES..1
(-1750 -2200);
FORCEPROP 1 LAST PART_NUMBER G21497-048
J 0
(-1650 -2200);
DISPLAY 0.617021 (-1650 -2200);
PAINT BLUE (-1650 -2200);
FORCEPROP 1 LASTPIN (-1650 -2200) $PN 2
J 0
(-1688 -2188);
DISPLAY 0.638298 (-1688 -2188);
PAINT ORANGE (-1688 -2188);
FORCEPROP 1 LAST LOCATION R1U14
J 0
(-2750 -2200);
DISPLAY 0.617021 (-2750 -2200);
PAINT AQUA (-2750 -2200);
FORCEPROP 1 LAST TOLERANCE 5.0%
J 0
(-2500 -2200);
DISPLAY 0.617021 (-2500 -2200);
PAINT SKYBLUE (-2500 -2200);
FORCEPROP 1 LAST VALUE 51
J 2
(-2550 -2200);
DISPLAY 0.617021 (-2550 -2200);
PAINT SKYBLUE (-2550 -2200);
FORCEPROP 1 LAST WATTAGE 1/16W
J 2
(-2225 -2200);
DISPLAY 0.617021 (-2225 -2200);
PAINT SKYBLUE (-2225 -2200);
FORCEPROP 1 LASTPIN (-1850 -2200) $PN 1
J 0
(-1838 -2188);
DISPLAY 0.638298 (-1838 -2188);
PAINT ORANGE (-1838 -2188);
FORCEPROP 1 LAST MATERIAL CHIP
J 0
(-2150 -2200);
DISPLAY 0.617021 (-2150 -2200);
PAINT SKYBLUE (-2150 -2200);
FORCEPROP 1 LAST PACK_TYPE 0402
J 0
(-2000 -2200);
DISPLAY 0.617021 (-2000 -2200);
PAINT SKYBLUE (-2000 -2200);
FORCEPROP 1 LAST PATH I57
J 0
(-1800 -2050);
DISPLAY 0.978723 (-1800 -2050);
PAINT WHITE (-1800 -2050);
DISPLAY INVISIBLE (-1800 -2050);
FORCEPROP 2 LAST CDS_LOCATION R1U14
J 0
(-1925 -2250);
DISPLAY 0.617021 (-1925 -2250);
PAINT AQUA (-1925 -2250);
DISPLAY INVISIBLE (-1925 -2250);
FORCEPROP 2 LAST CDS_LIB mstr_discrete
J 0
(-1750 -2200);
PAINT MONO (-1750 -2200);
DISPLAY INVISIBLE (-1750 -2200);
FORCEPROP 2 LAST ROOM BMC
J 0
(-1425 -2200);
PAINT MONO (-1425 -2200);
DISPLAY INVISIBLE (-1425 -2200);
FORCEPROP 2 LAST SEC_TYPE 0402
J 0
(-1800 -2000);
DISPLAY 1.021277 (-1800 -2000);
PAINT ORANGE (-1800 -2000);
DISPLAY INVISIBLE (-1800 -2000);
FORCEPROP 2 LAST SEC 1
J 0
(-1800 -2000);
PAINT MONO (-1800 -2000);
DISPLAY INVISIBLE (-1800 -2000);
FORCEADD RES..1
(-1750 -2050);
FORCEPROP 1 LAST PACK_TYPE 0402
J 0
(-2000 -2050);
DISPLAY 0.617021 (-2000 -2050);
PAINT SKYBLUE (-2000 -2050);
FORCEPROP 1 LAST MATERIAL CHIP
J 0
(-2150 -2050);
DISPLAY 0.617021 (-2150 -2050);
PAINT SKYBLUE (-2150 -2050);
FORCEPROP 1 LAST PART_NUMBER G21497-048
J 0
(-1650 -2050);
DISPLAY 0.617021 (-1650 -2050);
PAINT BLUE (-1650 -2050);
FORCEPROP 1 LAST TOLERANCE 5.0%
J 0
(-2500 -2050);
DISPLAY 0.617021 (-2500 -2050);
PAINT SKYBLUE (-2500 -2050);
FORCEPROP 1 LASTPIN (-1850 -2050) $PN 1
J 0
(-1838 -2038);
DISPLAY 0.638298 (-1838 -2038);
PAINT ORANGE (-1838 -2038);
FORCEPROP 1 LAST LOCATION R1U13
J 0
(-2750 -2050);
DISPLAY 0.617021 (-2750 -2050);
PAINT AQUA (-2750 -2050);
FORCEPROP 1 LAST VALUE 51
J 2
(-2550 -2050);
DISPLAY 0.617021 (-2550 -2050);
PAINT SKYBLUE (-2550 -2050);
FORCEPROP 1 LAST WATTAGE 1/16W
J 2
(-2225 -2050);
DISPLAY 0.617021 (-2225 -2050);
PAINT SKYBLUE (-2225 -2050);
FORCEPROP 1 LASTPIN (-1650 -2050) $PN 2
J 0
(-1688 -2038);
DISPLAY 0.638298 (-1688 -2038);
PAINT ORANGE (-1688 -2038);
FORCEPROP 1 LAST PATH I58
J 0
(-1800 -1900);
DISPLAY 0.978723 (-1800 -1900);
PAINT WHITE (-1800 -1900);
DISPLAY INVISIBLE (-1800 -1900);
FORCEPROP 2 LAST CDS_LOCATION R1U13
J 0
(-1925 -2100);
DISPLAY 0.617021 (-1925 -2100);
PAINT AQUA (-1925 -2100);
DISPLAY INVISIBLE (-1925 -2100);
FORCEPROP 2 LAST CDS_LIB mstr_discrete
J 0
(-1750 -2050);
PAINT MONO (-1750 -2050);
DISPLAY INVISIBLE (-1750 -2050);
FORCEPROP 2 LAST ROOM BMC
J 0
(-1425 -2050);
PAINT MONO (-1425 -2050);
DISPLAY INVISIBLE (-1425 -2050);
FORCEPROP 2 LAST SEC_TYPE 0402
J 0
(-1800 -1850);
DISPLAY 1.021277 (-1800 -1850);
PAINT ORANGE (-1800 -1850);
DISPLAY INVISIBLE (-1800 -1850);
FORCEPROP 2 LAST SEC 1
J 0
(-1800 -1850);
PAINT MONO (-1800 -1850);
DISPLAY INVISIBLE (-1800 -1850);
FORCEADD RES..1
(-1750 -2150);
FORCEPROP 1 LAST MATERIAL CHIP
J 0
(-2150 -2150);
DISPLAY 0.617021 (-2150 -2150);
PAINT SKYBLUE (-2150 -2150);
FORCEPROP 1 LASTPIN (-1850 -2150) $PN 1
J 0
(-1838 -2138);
DISPLAY 0.638298 (-1838 -2138);
PAINT ORANGE (-1838 -2138);
FORCEPROP 1 LASTPIN (-1650 -2150) $PN 2
J 0
(-1688 -2138);
DISPLAY 0.638298 (-1688 -2138);
PAINT ORANGE (-1688 -2138);
FORCEPROP 1 LAST PART_NUMBER G21497-048
J 0
(-1650 -2150);
DISPLAY 0.617021 (-1650 -2150);
PAINT BLUE (-1650 -2150);
FORCEPROP 1 LAST LOCATION R1U12
J 0
(-2750 -2150);
DISPLAY 0.617021 (-2750 -2150);
PAINT AQUA (-2750 -2150);
FORCEPROP 1 LAST TOLERANCE 5.0%
J 0
(-2500 -2150);
DISPLAY 0.617021 (-2500 -2150);
PAINT SKYBLUE (-2500 -2150);
FORCEPROP 1 LAST VALUE 51
J 2
(-2550 -2150);
DISPLAY 0.617021 (-2550 -2150);
PAINT SKYBLUE (-2550 -2150);
FORCEPROP 1 LAST WATTAGE 1/16W
J 2
(-2225 -2150);
DISPLAY 0.617021 (-2225 -2150);
PAINT SKYBLUE (-2225 -2150);
FORCEPROP 1 LAST PACK_TYPE 0402
J 0
(-2000 -2150);
DISPLAY 0.617021 (-2000 -2150);
PAINT SKYBLUE (-2000 -2150);
FORCEPROP 2 LAST SEC 1
J 0
(-1800 -1950);
PAINT MONO (-1800 -1950);
DISPLAY INVISIBLE (-1800 -1950);
FORCEPROP 1 LAST PATH I59
J 0
(-1800 -2000);
DISPLAY 0.978723 (-1800 -2000);
PAINT WHITE (-1800 -2000);
DISPLAY INVISIBLE (-1800 -2000);
FORCEPROP 2 LAST CDS_LOCATION R1U12
J 0
(-1775 -2100);
DISPLAY 0.617021 (-1775 -2100);
PAINT AQUA (-1775 -2100);
DISPLAY INVISIBLE (-1775 -2100);
FORCEPROP 2 LAST CDS_LIB mstr_discrete
J 0
(-1750 -2150);
PAINT MONO (-1750 -2150);
DISPLAY INVISIBLE (-1750 -2150);
FORCEPROP 2 LAST ROOM BMC
J 0
(-1425 -2150);
PAINT MONO (-1425 -2150);
DISPLAY INVISIBLE (-1425 -2150);
FORCEPROP 0 LAST SEC_TYPE 0402
J 0
(-2000 -2100);
DISPLAY 0.638298 (-2000 -2100);
PAINT SKYBLUE (-2000 -2100);
DISPLAY INVISIBLE (-2000 -2100);
FORCEADD OFFPAGE..2
(-2350 -3100);
FORCEPROP 2 LAST $XR1 255 
J 0
(-2041 -3100);
DISPLAY 0.638298 (-2041 -3100);
PAINT MONO (-2041 -3100);
FORCEPROP 2 LAST $XR0 189 
J 0
(-2161 -3100);
DISPLAY 0.638298 (-2161 -3100);
PAINT MONO (-2161 -3100);
FORCEPROP 2 LAST CDS_LIB mstr_standard
J 0
(-2350 -3100);
PAINT MONO (-2350 -3100);
DISPLAY INVISIBLE (-2350 -3100);
FORCEPROP 2 LAST PATH I67
J 0
(-2175 -3025);
DISPLAY 1.021277 (-2175 -3025);
PAINT ORANGE (-2175 -3025);
DISPLAY INVISIBLE (-2175 -3025);
FORCEPROP 1 LAST COMMENT_BODY TRUE
J 0
(-2395 -3195);
DISPLAY 0.872340 (-2395 -3195);
PAINT GREEN (-2395 -3195);
DISPLAY INVISIBLE (-2395 -3195);
FORCEPROP 1 LAST OFFPAGE TRUE
J 0
(-2025 -3225);
DISPLAY 0.872340 (-2025 -3225);
PAINT GREEN (-2025 -3225);
DISPLAY INVISIBLE (-2025 -3225);
FORCEADD OFFPAGE..4
(-2350 -3050);
FORCEPROP 2 LAST $XR1 255 
J 0
(-2044 -3050);
DISPLAY 0.638298 (-2044 -3050);
PAINT MONO (-2044 -3050);
FORCEPROP 2 LAST $XR0 189 
J 0
(-2164 -3050);
DISPLAY 0.638298 (-2164 -3050);
PAINT MONO (-2164 -3050);
FORCEPROP 2 LAST CDS_LIB mstr_standard
J 0
(-2350 -3050);
PAINT MONO (-2350 -3050);
DISPLAY INVISIBLE (-2350 -3050);
FORCEPROP 2 LAST PATH I70
J 0
(-2175 -2975);
DISPLAY 1.021277 (-2175 -2975);
PAINT ORANGE (-2175 -2975);
DISPLAY INVISIBLE (-2175 -2975);
FORCEPROP 1 LAST COMMENT_BODY TRUE
J 0
(-2375 -3150);
DISPLAY 0.872340 (-2375 -3150);
PAINT GREEN (-2375 -3150);
DISPLAY INVISIBLE (-2375 -3150);
FORCEPROP 1 LAST OFFPAGE TRUE
J 0
(-2025 -3175);
DISPLAY 0.872340 (-2025 -3175);
PAINT GREEN (-2025 -3175);
DISPLAY INVISIBLE (-2025 -3175);
FORCEADD GND..1
(-2400 -3750);
FORCEPROP 3 LASTPIN (-2400 -3700) SIG_NAME GND\g
J 0
(-2390 -3690);
DISPLAY 0.659574 (-2390 -3690);
PAINT MONO (-2390 -3690);
DISPLAY INVISIBLE (-2390 -3690);
FORCEPROP 1 LAST PATH I72
J 0
(-2366 -3709);
DISPLAY 0.872340 (-2366 -3709);
PAINT AQUA (-2366 -3709);
DISPLAY INVISIBLE (-2366 -3709);
FORCEPROP 2 LAST CDS_LIB mstr_symbols
J 0
(-2447 -3703);
PAINT ORANGE (-2447 -3703);
DISPLAY INVISIBLE (-2447 -3703);
FORCEPROP 1 LAST VOLTAGE 0.0V
J 0
(-2461 -3777);
DISPLAY 0.340426 (-2461 -3777);
PAINT SKYBLUE (-2461 -3777);
DISPLAY INVISIBLE (-2461 -3777);
FORCEPROP 1 LAST SIZE 1B
J 0
(-2366 -3759);
DISPLAY 0.872340 (-2366 -3759);
PAINT AQUA (-2366 -3759);
DISPLAY INVISIBLE (-2366 -3759);
FORCEPROP 1 LAST BODY_TYPE PLUMBING
J 0
(-2461 -3777);
DISPLAY 0.340426 (-2461 -3777);
PAINT GREEN (-2461 -3777);
DISPLAY INVISIBLE (-2461 -3777);
FORCEPROP 1 LAST HDL_POWER GND
J 0
(-2441 -3559);
DISPLAY 0.872340 (-2441 -3559);
PAINT GREEN (-2441 -3559);
DISPLAY INVISIBLE (-2441 -3559);
FORCEADD OFFPAGE..1
(-7350 -3400);
FORCEPROP 2 LAST $XR3 190 
J 0
(-7992 -3400);
DISPLAY 0.638298 (-7992 -3400);
PAINT MONO (-7992 -3400);
FORCEPROP 2 LAST $XR2 120 
J 0
(-7872 -3400);
DISPLAY 0.638298 (-7872 -3400);
PAINT MONO (-7872 -3400);
FORCEPROP 2 LAST $XR1 181 
J 0
(-7752 -3400);
DISPLAY 0.638298 (-7752 -3400);
PAINT MONO (-7752 -3400);
FORCEPROP 2 LAST $XR0 157 
J 0
(-7632 -3400);
DISPLAY 0.638298 (-7632 -3400);
PAINT MONO (-7632 -3400);
FORCEPROP 1 LAST COMMENT_BODY TRUE
J 0
(-7225 -3500);
DISPLAY 0.872340 (-7225 -3500);
PAINT GREEN (-7225 -3500);
DISPLAY INVISIBLE (-7225 -3500);
FORCEPROP 1 LAST OFFPAGE TRUE
J 0
(-7025 -3525);
DISPLAY 0.872340 (-7025 -3525);
PAINT GREEN (-7025 -3525);
DISPLAY INVISIBLE (-7025 -3525);
FORCEPROP 2 LAST ROOM BMC
J 0
(-7600 -3325);
DISPLAY 1.361702 (-7600 -3325);
PAINT ORANGE (-7600 -3325);
DISPLAY INVISIBLE (-7600 -3325);
FORCEPROP 2 LAST BOM_COST SM_CONTROLLER
J 0
(-6900 -3350);
PAINT MONO (-6900 -3350);
DISPLAY INVISIBLE (-6900 -3350);
FORCEPROP 2 LAST PATH I74
J 0
(-7300 -3325);
DISPLAY 1.021277 (-7300 -3325);
PAINT ORANGE (-7300 -3325);
DISPLAY INVISIBLE (-7300 -3325);
FORCEPROP 2 LAST CDS_LIB mstr_standard
J 0
(-7350 -3400);
PAINT MONO (-7350 -3400);
DISPLAY INVISIBLE (-7350 -3400);
FORCEADD OFFPAGE..1
(-7600 -4300);
FORCEPROP 2 LAST $XR0 114 
J 0
(-7852 -4300);
DISPLAY 0.638298 (-7852 -4300);
PAINT MONO (-7852 -4300);
FORCEPROP 1 LAST COMMENT_BODY TRUE
J 0
(-7475 -4400);
DISPLAY 0.872340 (-7475 -4400);
PAINT GREEN (-7475 -4400);
DISPLAY INVISIBLE (-7475 -4400);
FORCEPROP 1 LAST OFFPAGE TRUE
J 0
(-7275 -4425);
DISPLAY 0.872340 (-7275 -4425);
PAINT GREEN (-7275 -4425);
DISPLAY INVISIBLE (-7275 -4425);
FORCEPROP 2 LAST CDS_LIB mstr_standard
J 0
(-7600 -4300);
PAINT ORANGE (-7600 -4300);
DISPLAY INVISIBLE (-7600 -4300);
FORCEPROP 2 LAST ROOM BMC
J 0
(-7850 -4225);
DISPLAY 1.361702 (-7850 -4225);
PAINT ORANGE (-7850 -4225);
DISPLAY INVISIBLE (-7850 -4225);
FORCEPROP 2 LAST BOM_COST SM_CONTROLLER
J 0
(-7150 -4250);
PAINT MONO (-7150 -4250);
DISPLAY INVISIBLE (-7150 -4250);
FORCEPROP 2 LAST PATH I93
J 0
(-7850 -4250);
DISPLAY 1.021277 (-7850 -4250);
PAINT ORANGE (-7850 -4250);
DISPLAY INVISIBLE (-7850 -4250);
FORCEADD AST2520A1-GP-GP..2
(-4800 -2600);
FORCEPROP 1 LAST LOCATION U25W4
J 0
(-5950 -1425);
DISPLAY 0.617021 (-5950 -1425);
PAINT GREEN (-5950 -1425);
FORCEPROP 1 LAST VALUE AST2520A1-GP-GP
J 0
(-5950 -3800);
DISPLAY 0.617021 (-5950 -3800);
PAINT GREEN (-5950 -3800);
FORCEPROP 2 LAST CDS_LIB w_hdl
J 0
(-4800 -2600);
PAINT MONO (-4800 -2600);
DISPLAY INVISIBLE (-4800 -2600);
FORCEPROP 1 LAST CDS_LMAN_SYM_OUTLINE -1150,1150,1150,-1150
J 0
(-4800 -2600);
DISPLAY 0.468085 (-4800 -2600);
PAINT GREEN (-4800 -2600);
DISPLAY INVISIBLE (-4800 -2600);
FORCEPROP 1 LAST PATH I95
J 0
(-4800 -2600);
DISPLAY 0.617021 (-4800 -2600);
PAINT GREEN (-4800 -2600);
DISPLAY INVISIBLE (-4800 -2600);
FORCEPROP 1 LAST PART_NUMBER 071.2520A.M001
J 0
(-4800 -2600);
DISPLAY 0.617021 (-4800 -2600);
PAINT GREEN (-4800 -2600);
DISPLAY INVISIBLE (-4800 -2600);
FORCEPROP 1 LAST PACK_TYPE ASIC2-GB1
J 0
(-4800 -2600);
DISPLAY 0.617021 (-4800 -2600);
PAINT GREEN (-4800 -2600);
DISPLAY INVISIBLE (-4800 -2600);
FORCEADD OFFPAGE..3
R 2
(-7350 -3050);
FORCEPROP 2 LAST $XR0 160 
J 0
(-7630 -3050);
DISPLAY 0.638298 (-7630 -3050);
PAINT MONO (-7630 -3050);
FORCEPROP 2 LAST PATH I96
J 0
(-7625 -3000);
DISPLAY 1.021277 (-7625 -3000);
PAINT ORANGE (-7625 -3000);
DISPLAY INVISIBLE (-7625 -3000);
FORCEPROP 1 LAST COMMENT_BODY TRUE
J 2
(-7300 -3150);
DISPLAY 1.170213 (-7300 -3150);
PAINT GREEN (-7300 -3150);
DISPLAY INVISIBLE (-7300 -3150);
FORCEPROP 1 LAST OFFPAGE TRUE
J 2
(-7675 -3175);
PAINT GREEN (-7675 -3175);
DISPLAY INVISIBLE (-7675 -3175);
FORCEPROP 2 LAST ROOM BMC
J 2
(-7825 -3000);
PAINT MONO (-7825 -3000);
DISPLAY INVISIBLE (-7825 -3000);
FORCEPROP 2 LAST BOM_COST SM_CONTROLLER
J 2
(-7825 -3000);
PAINT MONO (-7825 -3000);
DISPLAY INVISIBLE (-7825 -3000);
FORCEPROP 2 LAST CDS_LIB mstr_standard
J 0
(-7350 -3050);
PAINT MONO (-7350 -3050);
DISPLAY INVISIBLE (-7350 -3050);
FORCEADD OFFPAGE..5
(-7350 -3100);
FORCEPROP 2 LAST $XR0 160 
J 0
(-7635 -3100);
DISPLAY 0.638298 (-7635 -3100);
PAINT MONO (-7635 -3100);
FORCEPROP 2 LAST CDS_LIB mstr_standard
J 0
(-7350 -3100);
PAINT MONO (-7350 -3100);
DISPLAY INVISIBLE (-7350 -3100);
FORCEPROP 1 LAST OFFPAGE TRUE
J 0
(-7025 -3225);
DISPLAY 0.872340 (-7025 -3225);
PAINT GREEN (-7025 -3225);
DISPLAY INVISIBLE (-7025 -3225);
FORCEPROP 1 LAST COMMENT_BODY TRUE
J 0
(-7250 -3175);
DISPLAY 0.872340 (-7250 -3175);
PAINT GREEN (-7250 -3175);
DISPLAY INVISIBLE (-7250 -3175);
FORCEPROP 2 LAST PATH I97
J 0
(-7600 -3050);
DISPLAY 1.021277 (-7600 -3050);
PAINT ORANGE (-7600 -3050);
DISPLAY INVISIBLE (-7600 -3050);
FORCEADD INTEL_CORP_BPAGE..1
(-75 -5650);
FORCEPROP 1 LAST CDS_CON_LAST_MODIFIED Fri Jun 16 17:48:54 2017
J 0
(-1500 -5325);
DISPLAY 1.361702 (-1500 -5325);
PAINT GREEN (-1500 -5325);
DISPLAY INVISIBLE (-1500 -5325);
FORCEPROP 1 LAST CUSTOM_TXT_CDS <CURRENT_DESIGN_SHEET> OF <TOTAL_DESIGN_SHEETS>
J 0
(-575 -5625);
PAINT ORANGE (-575 -5625);
FORCEPROP 1 LAST CUSTOM_TXT_CDS <CON_LAST_MODIFIED>
J 0
(-4075 -5550);
PAINT ORANGE (-4075 -5550);
FORCEPROP 2 LAST CUSTOM_TXT_CDS <XR_PAGE_TITLE>
J 0
(-7965 -400);
DISPLAY 0.638298 (-7965 -400);
PAINT PINK (-7965 -400);
DISPLAY INVISIBLE (-7965 -400);
FORCEPROP 1 LAST SCH_TITLE BMC (2 OF 7)
J 0
(-8025 -5600);
DISPLAY 1.212766 (-8025 -5600);
PAINT ORANGE (-8025 -5600);
FORCEPROP 2 LAST PAGE_BORDER TRUE
J 0
(-7965 -400);
DISPLAY 0.851064 (-7965 -400);
PAINT PINK (-7965 -400);
DISPLAY INVISIBLE (-7965 -400);
FORCEPROP 2 LAST CDS_LIB mstr_symbols
J 0
(-75 -5650);
DISPLAY 1.361702 (-75 -5650);
PAINT ORANGE (-75 -5650);
DISPLAY INVISIBLE (-75 -5650);
FORCEPROP 1 LAST COMMENT_BODY TRUE
J 0
(-63 -5638);
DISPLAY 0.617021 (-63 -5638);
PAINT GREEN (-63 -5638);
DISPLAY INVISIBLE (-63 -5638);
FORCEPROP 2 LAST CDS_XR_PAGE_TITLE CR-144 : @BASEBOARD_FAB2_LIB.BASEBOARD_FAB2(SCH_1):PAGE144
J 0
(-7965 -400);
DISPLAY 0.638298 (-7965 -400);
PAINT PINK (-7965 -400);
DISPLAY INVISIBLE (-7965 -400);
FORCEADD DNS..2
(-6695 -4280);
PAINT RED (-6695 -4280);
FORCEPROP 1 LAST COMMENT_BODY TRUE
R 1
J 0
(-6620 -4505);
DISPLAY 0.872340 (-6620 -4505);
PAINT GREEN (-6620 -4505);
DISPLAY INVISIBLE (-6620 -4505);
FORCEPROP 2 LAST CDS_LIB mstr_misc
J 0
(-6695 -4280);
PAINT ORANGE (-6695 -4280);
DISPLAY INVISIBLE (-6695 -4280);
WIRE 16 -1 (-2800 -4750)(-2800 -4650);
WIRE 16 -1 (-2450 -4750)(-2450 -4650);
WIRE 16 -1 (-2100 -4750)(-2100 -4650);
WIRE 16 -1 (-2400 -3650)(-2400 -3700);
WIRE 16 -1 (-6100 -2150)(-7300 -2150);
FORCEPROP 0 LAST SIG_NAME SMB_SENSOR_BMC_STBY_LVC3_SDA
J 0
(-7250 -2140);
DISPLAY 0.680851 (-7250 -2140);
PAINT ORANGE (-7250 -2140);
WIRE 16 -1 (-3500 -3250)(-2400 -3250);
FORCEPROP 2 LAST SIG_NAME BMC_VGA_GREEN
J 0
(-3285 -3240);
DISPLAY 0.680851 (-3285 -3240);
PAINT ORANGE (-3285 -3240);
WIRE 3 2175 (-3500 -4850)(-2000 -4850);
WIRE 3 2175 (-2000 -4150)(-2000 -4850);
WIRE 3 2175 (-3500 -4150)(-3500 -4850);
WIRE 3 2175 (-3500 -4150)(-2000 -4150);
WIRE 16 -1 (-2800 -4350)(-3450 -4350);
FORCEPROP 2 LAST SIG_NAME BMC_VGA_BLUE
J 0
(-3385 -4340);
DISPLAY 0.680851 (-3385 -4340);
PAINT ORANGE (-3385 -4340);
FORCEPROP 2 LASTPROP $XR1 252 
J 0
(-3726 -4350);
DISPLAY 0.638298 (-3726 -4350);
PAINT MONO (-3726 -4350);
FORCEPROP 2 LASTPROP $XR0 144 
J 0
(-3606 -4350);
DISPLAY 0.638298 (-3606 -4350);
PAINT MONO (-3606 -4350);
WIRE 16 -1 (-2800 -4450)(-2800 -4350);
WIRE 16 -1 (-1650 -2800)(-650 -2800);
FORCEPROP 2 LAST SIG_NAME FM_CPU0_FIVR_FAULT_LVT3_N
J 0
(-1335 -2790);
DISPLAY 0.617021 (-1335 -2790);
PAINT ORANGE (-1335 -2790);
WIRE 16 -1 (-6100 -2800)(-7300 -2800);
FORCEPROP 0 LAST SIG_NAME SMB_OCP_LAN_STBY_LVC3_SCL_R
J 0
(-7250 -2790);
DISPLAY 0.680851 (-7250 -2790);
PAINT ORANGE (-7250 -2790);
WIRE 16 -1 (-6100 -2900)(-7300 -2900);
FORCEPROP 0 LAST CDS_PHYS_NET_NAME SMB_SLOTX24_STBY_LVC3_SDA_R
J 0
(-7275 -2858);
PAINT MONO (-7275 -2858);
DISPLAY INVISIBLE (-7275 -2858);
FORCEPROP 0 LAST SIG_NAME SMB_SLOTX24_STBY_LVC3_SDA_R
J 0
(-7250 -2890);
DISPLAY 0.680851 (-7250 -2890);
PAINT ORANGE (-7250 -2890);
WIRE 3 682 (-7800 -3350)(-8000 -3350);
WIRE 3 682 (-8000 -3350)(-8000 -3200);
WIRE 3 682 (-8000 -3200)(-7900 -3200);
WIRE 16 -1 (-6100 -3350)(-7300 -3350);
FORCEPROP 2 LAST SIG_NAME BMC_DEBUG_EN_N
J 0
(-7235 -3340);
DISPLAY 0.638298 (-7235 -3340);
PAINT ORANGE (-7235 -3340);
WIRE 16 -1 (-7300 -3400)(-6100 -3400);
FORCEPROP 0 LAST CDS_PHYS_NET_NAME H_CPU0_FAST_WAKE_LVT3_N
J 0
(-6100 -3361);
PAINT MONO (-6100 -3361);
DISPLAY INVISIBLE (-6100 -3361);
FORCEPROP 0 LAST PHYS_NET_NAME H_CPU0_FAST_WAKE_LVT3_N
J 0
(-6100 -3314);
PAINT MONO (-6100 -3314);
DISPLAY INVISIBLE (-6100 -3314);
FORCEPROP 0 LAST SIG_NAME FM_MP_PS_FAIL_N
J 0
(-7250 -3390);
DISPLAY 0.680851 (-7250 -3390);
PAINT ORANGE (-7250 -3390);
WIRE 16 -1 (-6100 -2950)(-7300 -2950);
FORCEPROP 0 LAST CDS_PHYS_NET_NAME SMB_SLOTX24_STBY_LVC3_SCL_R
J 0
(-7250 -2908);
PAINT MONO (-7250 -2908);
DISPLAY INVISIBLE (-7250 -2908);
FORCEPROP 0 LAST SIG_NAME SMB_SLOTX24_STBY_LVC3_SCL_R
J 0
(-7250 -2940);
DISPLAY 0.680851 (-7250 -2940);
PAINT ORANGE (-7250 -2940);
WIRE 16 -1 (-7300 -3100)(-6100 -3100);
FORCEPROP 0 LAST CDS_PHYS_NET_NAME H_CPU0_FAST_WAKE_LVT3_N
J 0
(-6100 -3061);
PAINT MONO (-6100 -3061);
DISPLAY INVISIBLE (-6100 -3061);
FORCEPROP 0 LAST SIG_NAME SMB_LAN_STBY_LVC3_SCL_R
J 0
(-7250 -3090);
DISPLAY 0.680851 (-7250 -3090);
PAINT ORANGE (-7250 -3090);
FORCEPROP 0 LAST PHYS_NET_NAME H_CPU0_FAST_WAKE_LVT3_N
J 0
(-6100 -3014);
PAINT MONO (-6100 -3014);
DISPLAY INVISIBLE (-6100 -3014);
WIRE 16 -1 (-7300 -3050)(-6100 -3050);
FORCEPROP 0 LAST CDS_PHYS_NET_NAME H_CPU0_FAST_WAKE_LVT3_N
J 0
(-6100 -3011);
PAINT MONO (-6100 -3011);
DISPLAY INVISIBLE (-6100 -3011);
FORCEPROP 0 LAST SIG_NAME SMB_LAN_STBY_LVC3_SDA_R
J 0
(-7250 -3040);
DISPLAY 0.680851 (-7250 -3040);
PAINT ORANGE (-7250 -3040);
FORCEPROP 0 LAST PHYS_NET_NAME H_CPU0_FAST_WAKE_LVT3_N
J 0
(-6100 -2964);
PAINT MONO (-6100 -2964);
DISPLAY INVISIBLE (-6100 -2964);
WIRE 16 -1 (-7300 -3450)(-6100 -3450);
FORCEPROP 0 LAST CDS_PHYS_NET_NAME H_CPU0_FAST_WAKE_LVT3_N
J 0
(-6100 -3411);
PAINT MONO (-6100 -3411);
DISPLAY INVISIBLE (-6100 -3411);
FORCEPROP 0 LAST SIG_NAME H_CPU0_FAST_WAKE_LVT3_N
J 0
(-7250 -3440);
DISPLAY 0.680851 (-7250 -3440);
PAINT ORANGE (-7250 -3440);
FORCEPROP 0 LAST PHYS_NET_NAME H_CPU0_FAST_WAKE_LVT3_N
J 0
(-6100 -3364);
PAINT MONO (-6100 -3364);
DISPLAY INVISIBLE (-6100 -3364);
WIRE 16 -1 (-7300 -3550)(-6100 -3550);
FORCEPROP 0 LAST SIG_NAME IRQ_BMC_PCH_SMI_LPC_N
J 0
(-7250 -3540);
DISPLAY 0.680851 (-7250 -3540);
PAINT ORANGE (-7250 -3540);
WIRE 16 -1 (-6300 -4050)(-6600 -4050);
WIRE 16 -1 (-6300 -3600)(-6300 -4050);
WIRE 16 -1 (-6300 -3600)(-6100 -3600);
WIRE 16 -1 (-7300 -3600)(-6300 -3600);
FORCEPROP 0 LAST SIG_NAME PWRGD_SYS_PWROK
J 0
(-7250 -3590);
DISPLAY 0.680851 (-7250 -3590);
PAINT ORANGE (-7250 -3590);
WIRE 16 -1 (-6100 -3500)(-6250 -3500);
WIRE 16 -1 (-6600 -4300)(-6250 -4300);
WIRE 16 -1 (-6250 -4300)(-6250 -3500);
FORCEPROP 2 LAST SIG_NAME CLK_48M_USB_BMC_R
R 1
J 0
(-6260 -4240);
DISPLAY 0.638298 (-6260 -4240);
PAINT ORANGE (-6260 -4240);
FORCEPROP 2 LASTPROP $XRERR UNIQUE?
J 0
(-6500 -4240);
DISPLAY 0.638298 (-6500 -4240);
PAINT MONO (-6500 -4240);
DISPLAY INVISIBLE (-6500 -4240);
WIRE 16 -1 (-7550 -4050)(-6800 -4050);
FORCEPROP 2 LAST SIG_NAME XDP_SYSPWROK
J 0
(-7485 -4040);
DISPLAY 0.638298 (-7485 -4040);
PAINT ORANGE (-7485 -4040);
WIRE 16 -1 (-7300 -3300)(-6100 -3300);
FORCEPROP 0 LAST CDS_PHYS_NET_NAME H_CPU0_FAST_WAKE_LVT3_N
J 0
(-6100 -3261);
PAINT MONO (-6100 -3261);
DISPLAY INVISIBLE (-6100 -3261);
FORCEPROP 0 LAST PHYS_NET_NAME H_CPU0_FAST_WAKE_LVT3_N
J 0
(-6100 -3214);
PAINT MONO (-6100 -3214);
DISPLAY INVISIBLE (-6100 -3214);
FORCEPROP 0 LAST SIG_NAME PWRGD_PCH_PWROK
J 0
(-7250 -3290);
DISPLAY 0.680851 (-7250 -3290);
PAINT ORANGE (-7250 -3290);
WIRE 16 -1 (-7300 -3650)(-6100 -3650);
FORCEPROP 0 LAST SIG_NAME IRQ_PVDDQ_GHJ_VRHOT_LVT3_N
J 0
(-7250 -3640);
DISPLAY 0.680851 (-7250 -3640);
PAINT ORANGE (-7250 -3640);
WIRE 16 -1 (-7550 -4300)(-6800 -4300);
FORCEPROP 0 LAST SIG_NAME CLK_48M_USB_BMC
J 0
(-7500 -4290);
DISPLAY 0.680851 (-7500 -4290);
PAINT ORANGE (-7500 -4290);
WIRE 16 -1 (-2400 -3350)(-3500 -3350);
FORCEPROP 2 LAST SIG_NAME A_DACRSET
J 0
(-3285 -3340);
DISPLAY 0.680851 (-3285 -3340);
PAINT ORANGE (-3285 -3340);
FORCEPROP 2 LASTPROP $XRERR UNIQUE?
J 0
(-3525 -3340);
DISPLAY 0.638298 (-3525 -3340);
PAINT MONO (-3525 -3340);
DISPLAY INVISIBLE (-3525 -3340);
WIRE 16 -1 (-2400 -3400)(-2400 -3350);
WIRE 16 -1 (-3500 -2050)(-1850 -2050);
FORCEPROP 2 LAST SIG_NAME SGPIO_BMC_DOUT_R
J 0
(-3300 -2040);
DISPLAY 0.680851 (-3300 -2040);
PAINT ORANGE (-3300 -2040);
FORCEPROP 2 LASTPROP $XRERR UNIQUE?
J 0
(-3540 -2040);
DISPLAY 0.638298 (-3540 -2040);
PAINT MONO (-3540 -2040);
DISPLAY INVISIBLE (-3540 -2040);
WIRE 16 -1 (-3500 -1750)(-2400 -1750);
FORCEPROP 2 LAST SIG_NAME FM_PCH_BMC_THERMTRIP_N
J 0
(-3285 -1740);
DISPLAY 0.680851 (-3285 -1740);
PAINT ORANGE (-3285 -1740);
WIRE 16 -1 (-3500 -1700)(-2400 -1700);
FORCEPROP 2 LAST SIG_NAME FM_CPU0_SKTOCC_LVT3_N
J 0
(-3285 -1690);
DISPLAY 0.680851 (-3285 -1690);
PAINT ORANGE (-3285 -1690);
WIRE 16 -1 (-3500 -2500)(-2400 -2500);
FORCEPROP 2 LAST SIG_NAME SPI_BMC_CS0_N
J 0
(-3300 -2490);
DISPLAY 0.680851 (-3300 -2490);
PAINT ORANGE (-3300 -2490);
WIRE 16 -1 (-3500 -2300)(-2400 -2300);
FORCEPROP 2 LAST SIG_NAME SPI_BMC_DI
J 0
(-3300 -2290);
DISPLAY 0.680851 (-3300 -2290);
PAINT ORANGE (-3300 -2290);
WIRE 16 -1 (-3500 -2200)(-1850 -2200);
FORCEPROP 2 LAST SIG_NAME SGPIO_BMC_CLK_R
J 0
(-3300 -2190);
DISPLAY 0.680851 (-3300 -2190);
PAINT ORANGE (-3300 -2190);
FORCEPROP 2 LASTPROP $XRERR UNIQUE?
J 0
(-3540 -2190);
DISPLAY 0.638298 (-3540 -2190);
PAINT MONO (-3540 -2190);
DISPLAY INVISIBLE (-3540 -2190);
WIRE 16 -1 (-650 -2000)(-3500 -2000);
FORCEPROP 2 LAST SIG_NAME SGPIO_BMC_DIN
J 0
(-3300 -1990);
DISPLAY 0.680851 (-3300 -1990);
PAINT ORANGE (-3300 -1990);
WIRE 16 -1 (-1650 -2050)(-650 -2050);
FORCEPROP 2 LAST SIG_NAME SGPIO_BMC_DOUT
J 0
(-1350 -2040);
DISPLAY 0.680851 (-1350 -2040);
PAINT ORANGE (-1350 -2040);
WIRE 16 -1 (-1650 -2150)(-650 -2150);
FORCEPROP 2 LAST SIG_NAME SGPIO_BMC_LD_N
J 0
(-1350 -2140);
DISPLAY 0.680851 (-1350 -2140);
PAINT ORANGE (-1350 -2140);
WIRE 16 -1 (-2100 -4250)(-2100 -4450);
WIRE 16 -1 (-3450 -4250)(-2100 -4250);
FORCEPROP 2 LAST SIG_NAME BMC_VGA_RED
J 0
(-3385 -4240);
DISPLAY 0.680851 (-3385 -4240);
PAINT ORANGE (-3385 -4240);
FORCEPROP 2 LASTPROP $XR1 252 
J 0
(-3726 -4250);
DISPLAY 0.638298 (-3726 -4250);
PAINT MONO (-3726 -4250);
FORCEPROP 2 LASTPROP $XR0 144 
J 0
(-3606 -4250);
DISPLAY 0.638298 (-3606 -4250);
PAINT MONO (-3606 -4250);
WIRE 16 -1 (-2400 -3150)(-3500 -3150);
FORCEPROP 2 LAST SIG_NAME PU_JTAG_BMC_RTCK
J 0
(-3285 -3140);
DISPLAY 0.680851 (-3285 -3140);
PAINT ORANGE (-3285 -3140);
WIRE 16 -1 (-3500 -3300)(-2400 -3300);
FORCEPROP 2 LAST SIG_NAME BMC_VGA_BLUE
J 0
(-3285 -3290);
DISPLAY 0.680851 (-3285 -3290);
PAINT ORANGE (-3285 -3290);
WIRE 16 -1 (-3500 -3200)(-2400 -3200);
FORCEPROP 2 LAST SIG_NAME BMC_VGA_RED
J 0
(-3285 -3190);
DISPLAY 0.680851 (-3285 -3190);
PAINT ORANGE (-3285 -3190);
WIRE 16 -1 (-3500 -2150)(-1850 -2150);
FORCEPROP 2 LAST SIG_NAME SGPIO_BMC_LD_R_N
J 0
(-3300 -2140);
DISPLAY 0.680851 (-3300 -2140);
PAINT ORANGE (-3300 -2140);
FORCEPROP 2 LASTPROP $XRERR UNIQUE?
J 0
(-3540 -2140);
DISPLAY 0.638298 (-3540 -2140);
PAINT MONO (-3540 -2140);
DISPLAY INVISIBLE (-3540 -2140);
WIRE 16 -1 (-1650 -2200)(-650 -2200);
FORCEPROP 2 LAST SIG_NAME SGPIO_BMC_CLK
J 0
(-1350 -2190);
DISPLAY 0.680851 (-1350 -2190);
PAINT ORANGE (-1350 -2190);
WIRE 16 -1 (-3500 -1850)(-2400 -1850);
FORCEPROP 2 LAST SIG_NAME FM_CPU_CATERR_LVT3_N
J 0
(-3285 -1840);
DISPLAY 0.680851 (-3285 -1840);
PAINT ORANGE (-3285 -1840);
WIRE 16 -1 (-3500 -1900)(-2400 -1900);
FORCEPROP 2 LAST SIG_NAME FM_CPU_ERR2_LVT3_N
J 0
(-3285 -1890);
DISPLAY 0.680851 (-3285 -1890);
PAINT ORANGE (-3285 -1890);
WIRE 16 -1 (-2400 -2900)(-3500 -2900);
FORCEPROP 2 LAST SIG_NAME JTAG_BMC_TRST_N
J 0
(-3285 -2890);
DISPLAY 0.680851 (-3285 -2890);
PAINT ORANGE (-3285 -2890);
WIRE 16 -1 (-2400 -2950)(-3500 -2950);
FORCEPROP 2 LAST SIG_NAME JTAG_BMC_TCK
J 0
(-3285 -2940);
DISPLAY 0.680851 (-3285 -2940);
PAINT ORANGE (-3285 -2940);
WIRE 16 -1 (-2400 -3000)(-3500 -3000);
FORCEPROP 2 LAST SIG_NAME JTAG_BMC_TMS
J 0
(-3285 -2990);
DISPLAY 0.680851 (-3285 -2990);
PAINT ORANGE (-3285 -2990);
WIRE 16 -1 (-2400 -3050)(-3500 -3050);
FORCEPROP 2 LAST SIG_NAME JTAG_BMC_TDI
J 0
(-3285 -3040);
DISPLAY 0.680851 (-3285 -3040);
PAINT ORANGE (-3285 -3040);
WIRE 16 -1 (-2400 -3100)(-3500 -3100);
FORCEPROP 2 LAST SIG_NAME JTAG_BMC_TDO
J 0
(-3285 -3090);
DISPLAY 0.680851 (-3285 -3090);
PAINT ORANGE (-3285 -3090);
WIRE 16 -1 (-7300 -1700)(-6100 -1700);
FORCEPROP 2 LAST SIG_NAME FM_UARTSW_MSB_N
J 0
(-7235 -1690);
DISPLAY 0.680851 (-7235 -1690);
PAINT ORANGE (-7235 -1690);
WIRE 16 -1 (-7300 -1750)(-6100 -1750);
FORCEPROP 2 LAST SIG_NAME FM_UARTSW_LSB_N
J 0
(-7235 -1740);
DISPLAY 0.680851 (-7235 -1740);
PAINT ORANGE (-7235 -1740);
WIRE 16 -1 (-7300 -2750)(-6100 -2750);
FORCEPROP 0 LAST SIG_NAME SMB_OCP_LAN_STBY_LVC3_SDA_R
J 0
(-7250 -2740);
DISPLAY 0.680851 (-7250 -2740);
PAINT ORANGE (-7250 -2740);
WIRE 16 -1 (-6100 -2650)(-7300 -2650);
FORCEPROP 0 LAST SIG_NAME SMB_HOST_STBY_LVC3_SCL_R
J 0
(-7250 -2640);
DISPLAY 0.680851 (-7250 -2640);
PAINT ORANGE (-7250 -2640);
WIRE 16 -1 (-6100 -2500)(-7300 -2500);
FORCEPROP 0 LAST SIG_NAME SMB_SMLINK0_STBY_LVC3_SCL_R
J 0
(-7250 -2490);
DISPLAY 0.680851 (-7250 -2490);
PAINT ORANGE (-7250 -2490);
WIRE 16 -1 (-6100 -2450)(-7300 -2450);
FORCEPROP 0 LAST SIG_NAME SMB_SMLINK0_STBY_LVC3_SDA_R
J 0
(-7250 -2440);
DISPLAY 0.680851 (-7250 -2440);
PAINT ORANGE (-7250 -2440);
WIRE 16 -1 (-6100 -2350)(-7300 -2350);
FORCEPROP 0 LAST SIG_NAME SMB_VR_STBY_LVC3_SCL_R
J 0
(-7250 -2340);
DISPLAY 0.680851 (-7250 -2340);
PAINT ORANGE (-7250 -2340);
WIRE 16 -1 (-6100 -2300)(-7300 -2300);
FORCEPROP 0 LAST SIG_NAME SMB_VR_STBY_LVC3_SDA_R
J 0
(-7250 -2290);
DISPLAY 0.680851 (-7250 -2290);
PAINT ORANGE (-7250 -2290);
WIRE 16 -1 (-6100 -2200)(-7300 -2200);
FORCEPROP 0 LAST SIG_NAME SMB_SENSOR_BMC_STBY_LVC3_SCL
J 0
(-7250 -2190);
DISPLAY 0.680851 (-7250 -2190);
PAINT ORANGE (-7250 -2190);
WIRE 16 -1 (-7300 -1900)(-6100 -1900);
FORCEPROP 0 LAST SIG_NAME SMB_OCP_FRU_STBY_LVC3_SCL_R
J 0
(-7250 -1890);
DISPLAY 0.680851 (-7250 -1890);
PAINT ORANGE (-7250 -1890);
WIRE 16 -1 (-6100 -2000)(-7300 -2000);
FORCEPROP 0 LAST SIG_NAME SMB_BMC_PMBUS_STBY_LVC3_SDA_R
J 0
(-7250 -1990);
DISPLAY 0.680851 (-7250 -1990);
PAINT ORANGE (-7250 -1990);
WIRE 16 -1 (-7300 -2050)(-6100 -2050);
FORCEPROP 0 LAST SIG_NAME SMB_BMC_PMBUS_STBY_LVC3_SCL_R
J 0
(-7250 -2040);
DISPLAY 0.680851 (-7250 -2040);
PAINT ORANGE (-7250 -2040);
WIRE 16 -1 (-2450 -4300)(-2450 -4450);
WIRE 16 -1 (-3450 -4300)(-2450 -4300);
FORCEPROP 2 LAST SIG_NAME BMC_VGA_GREEN
J 0
(-3385 -4290);
DISPLAY 0.680851 (-3385 -4290);
PAINT ORANGE (-3385 -4290);
FORCEPROP 2 LASTPROP $XR1 252 
J 0
(-3726 -4300);
DISPLAY 0.638298 (-3726 -4300);
PAINT MONO (-3726 -4300);
FORCEPROP 2 LASTPROP $XR0 144 
J 0
(-3606 -4300);
DISPLAY 0.638298 (-3606 -4300);
PAINT MONO (-3606 -4300);
WIRE 16 -1 (-1650 -2750)(-650 -2750);
FORCEPROP 2 LAST SIG_NAME FM_CPU1_FIVR_FAULT_LVT3_N
J 0
(-1335 -2740);
DISPLAY 0.617021 (-1335 -2740);
PAINT ORANGE (-1335 -2740);
WIRE 16 -1 (-3500 -2450)(-2400 -2450);
FORCEPROP 2 LAST SIG_NAME SPI_BMC_CLK
J 0
(-3300 -2440);
DISPLAY 0.680851 (-3300 -2440);
PAINT ORANGE (-3300 -2440);
WIRE 16 -1 (-3500 -2350)(-2400 -2350);
FORCEPROP 0 LAST CDS_PHYS_NET_NAME SPI_BMC_DO
J 0
(-3100 -2308);
PAINT MONO (-3100 -2308);
DISPLAY INVISIBLE (-3100 -2308);
FORCEPROP 2 LAST SIG_NAME SPI_BMC_DO
J 0
(-3300 -2340);
DISPLAY 0.680851 (-3300 -2340);
PAINT ORANGE (-3300 -2340);
WIRE 16 -1 (-3500 -2600)(-2400 -2600);
FORCEPROP 0 LAST CDS_PHYS_NET_NAME FM_UV_ADR_TRIGGER_EN
J 0
(-3385 -2558);
PAINT MONO (-3385 -2558);
DISPLAY INVISIBLE (-3385 -2558);
FORCEPROP 2 LAST SIG_NAME FM_UV_ADR_TRIGGER_EN
J 0
(-3285 -2590);
DISPLAY 0.680851 (-3285 -2590);
PAINT ORANGE (-3285 -2590);
WIRE 16 -1 (-6100 -2600)(-7300 -2600);
FORCEPROP 0 LAST SIG_NAME SMB_HOST_STBY_LVC3_SDA_R
J 0
(-7250 -2590);
DISPLAY 0.680851 (-7250 -2590);
PAINT ORANGE (-7250 -2590);
WIRE 16 -1 (-6100 -1850)(-7300 -1850);
FORCEPROP 0 LAST SIG_NAME SMB_OCP_FRU_STBY_LVC3_SDA_R
J 0
(-7250 -1840);
DISPLAY 0.680851 (-7250 -1840);
PAINT ORANGE (-7250 -1840);
WIRE 16 -1 (-3500 -2650)(-2400 -2650);
FORCEPROP 0 LAST $PHYS_NET_NAME FM_FORCE_ADR_N
J 0
(-3335 -2561);
PAINT MONO (-3335 -2561);
DISPLAY INVISIBLE (-3335 -2561);
FORCEPROP 0 LAST CDS_PHYS_NET_NAME FM_FORCE_ADR_N
J 0
(-3335 -2608);
PAINT MONO (-3335 -2608);
DISPLAY INVISIBLE (-3335 -2608);
FORCEPROP 2 LAST SIG_NAME FM_FORCE_ADR_N
J 0
(-3285 -2640);
DISPLAY 0.680851 (-3285 -2640);
PAINT ORANGE (-3285 -2640);
WIRE 16 -1 (-3500 -2750)(-1850 -2750);
FORCEPROP 2 LAST SIG_NAME FM_CPU1_FIVR_FAULT_LVT3_R_N
J 0
(-3285 -2740);
DISPLAY 0.617021 (-3285 -2740);
PAINT ORANGE (-3285 -2740);
FORCEPROP 2 LASTPROP $XRERR UNIQUE?
J 0
(-3525 -2740);
DISPLAY 0.638298 (-3525 -2740);
PAINT MONO (-3525 -2740);
DISPLAY INVISIBLE (-3525 -2740);
WIRE 16 -1 (-3500 -2800)(-1850 -2800);
FORCEPROP 2 LAST SIG_NAME FM_CPU0_FIVR_FAULT_LVT3_R_N
J 0
(-3285 -2790);
DISPLAY 0.617021 (-3285 -2790);
PAINT ORANGE (-3285 -2790);
FORCEPROP 2 LASTPROP $XRERR UNIQUE?
J 0
(-3525 -2790);
DISPLAY 0.638298 (-3525 -2790);
PAINT MONO (-3525 -2790);
DISPLAY INVISIBLE (-3525 -2790);
DOT 1 (-6300 -3600);
FORCENOTE
TP FAB3 RECONNECT 0922
(-7875 -3225) 0;
DISPLAY LEFT (-7875 -3225);
DISPLAY 1.021277 (-7875 -3225);
PAINT RED (-7875 -3225);
FORCENOTE
TP FAB3 NOPOP R25W182 0922
(-7550 -4150) 0;
DISPLAY LEFT (-7550 -4150);
DISPLAY 0.638298 (-7550 -4150);
PAINT RED (-7550 -4150);
FORCENOTE
TP FAB3 ADD R25W182 0921
(-7550 -4100) 0;
DISPLAY LEFT (-7550 -4100);
DISPLAY 0.638298 (-7550 -4100);
PAINT RED (-7550 -4100);
FORCENOTE
BOM_COST=SM_CONTROLLER
(-8000 -5475) 0;
DISPLAY LEFT (-8000 -5475);
DISPLAY 1.595745 (-8000 -5475);
PAINT PURPLE (-8000 -5475);
FORCENOTE
ROOM=BMC
(-7975 -5350) 0;
DISPLAY LEFT (-7975 -5350);
DISPLAY 1.595745 (-7975 -5350);
PAINT PURPLE (-7975 -5350);
FORCENOTE
TP FAB1 ADD RES 1230
(-3500 -4950) 0;
DISPLAY LEFT (-3500 -4950);
DISPLAY 1.021277 (-3500 -4950);
PAINT RED (-3500 -4950);
FORCENOTE
TP FAB1 ADD CONFIG/AST2500 ON RES 0118
(-3500 -5000) 0;
DISPLAY LEFT (-3500 -5000);
DISPLAY 1.021277 (-3500 -5000);
PAINT RED (-3500 -5000);
FORCENOTE
USB CLOCK IS FROM BMC INTERNAL
(-7325 -4525) 0;
DISPLAY LEFT (-7325 -4525);
DISPLAY 1.021277 (-7325 -4525);
PAINT PURPLE (-7325 -4525);
FORCENOTE
$CDS_IMAGE|圖片 1.jpg|1162|450
(-6775 -4775) 0;
DISPLAY LEFT (-6775 -4775);
QUIT
